G04 ================== begin FILE IDENTIFICATION RECORD ==================*
G04 Layout Name:  15669-1.brd*
G04 Film Name:    DP_REF_L3*
G04 File Format:  Gerber RS274X*
G04 File Origin:  Cadence Allegro 16.5-S056*
G04 Origin Date:  Wed Nov 16 04:09:14 2016*
G04 *
G04 Layer:  BOARD GEOMETRY/DP_REF_L3_TBL*
G04 Layer:  BOARD GEOMETRY/DP_REF_L3_L3*
G04 Layer:  BOARD GEOMETRY/PANEL_OUTLINE*
G04 *
G04 Offset:    (0.00 0.00)*
G04 Mirror:    No*
G04 Mode:      Positive*
G04 Rotation:  0*
G04 FullContactRelief:  No*
G04 UndefLineWidth:     6.00*
G04 ================== end FILE IDENTIFICATION RECORD ====================*
%FSLAX35Y35*MOIN*%
%IR0*IPPOS*OFA0.00000B0.00000*MIA0B0*SFA1.00000B1.00000*%
%ADD10C,.02*%
%ADD11C,.006*%
%ADD12C,.0065*%
G75*
%LPD*%
G75*
G54D10*
G01X1178253Y1853826D02*
X1965753D01*
G01X1178253Y1957776D02*
Y1853826D01*
G01Y1923126D02*
X1965753D01*
G01X1178253Y1888476D02*
X1965753D01*
G01X1178253Y1957776D02*
X1965753D01*
G01X1353253D02*
Y1853826D01*
G01X1650753Y1957776D02*
Y1853826D01*
G01X1755753Y1957776D02*
Y1853826D01*
G01X1965753Y1957776D02*
Y1853826D01*
G54D11*
G01X-84302Y-32800D02*
Y-50300D01*
G01X-89324Y-32800D02*
X-79280D01*
G01X-70514Y-50300D02*
Y-32800D01*
G01Y-41258D02*
X-69422Y-39800D01*
X-68330Y-38925D01*
X-66584Y-38634D01*
X-65274Y-38925D01*
X-63745Y-40092D01*
X-63090Y-41842D01*
Y-50300D01*
G01X-49302Y-38634D02*
Y-50300D01*
G01Y-33967D02*
X-49739Y-33675D01*
Y-33092D01*
X-49302Y-32800D01*
X-48865Y-33092D01*
Y-33675D01*
X-49302Y-33967D01*
G01X-35077Y-48259D02*
X-33985Y-49425D01*
X-32457Y-50300D01*
X-31147D01*
X-29837Y-49717D01*
X-28964Y-48842D01*
X-28527Y-47676D01*
X-28745Y-45925D01*
X-29619Y-45050D01*
X-33549Y-43300D01*
X-34422Y-41258D01*
X-33985Y-39800D01*
X-33112Y-38925D01*
X-31802Y-38634D01*
X-30492Y-38925D01*
X-29182Y-39800D01*
G01X141Y-54675D02*
X1670Y-55842D01*
X3416Y-56133D01*
X4944Y-55842D01*
X6255Y-54384D01*
X7128Y-52342D01*
Y-38634D01*
G01Y-40967D02*
X6255Y-39800D01*
X4944Y-38925D01*
X3416Y-38634D01*
X1670Y-39217D01*
X578Y-40383D01*
X-296Y-42425D01*
X-732Y-44467D01*
X-514Y-46217D01*
X360Y-48259D01*
X1670Y-49717D01*
X3416Y-50300D01*
X4726Y-50008D01*
X6255Y-48842D01*
X7128Y-47676D01*
G01X17423Y-42425D02*
X24410D01*
X23755Y-40383D01*
X22663Y-39217D01*
X21135Y-38634D01*
X19606Y-38925D01*
X18296Y-39800D01*
X17423Y-41842D01*
X16986Y-43592D01*
Y-45342D01*
X17423Y-47092D01*
X18515Y-48842D01*
X19825Y-50008D01*
X21353Y-50300D01*
X22881Y-49717D01*
X24410Y-47967D01*
G01X35141Y-50300D02*
Y-38634D01*
G01Y-40967D02*
X36233Y-39800D01*
X37325Y-38925D01*
X38853Y-38634D01*
X39944Y-38925D01*
X41255Y-39800D01*
G01X51768Y-50300D02*
Y-32800D01*
G01Y-41550D02*
X52860Y-39800D01*
X54170Y-38925D01*
X55480Y-38634D01*
X57444Y-39217D01*
X58755Y-40383D01*
X59628Y-42425D01*
Y-44758D01*
X59191Y-47092D01*
X58318Y-48842D01*
X56790Y-50008D01*
X55480Y-50300D01*
X54170Y-50008D01*
X52860Y-49134D01*
X51768Y-47676D01*
G01X69923Y-42425D02*
X76910D01*
X76255Y-40383D01*
X75163Y-39217D01*
X73635Y-38634D01*
X72106Y-38925D01*
X70796Y-39800D01*
X69923Y-41842D01*
X69486Y-43592D01*
Y-45342D01*
X69923Y-47092D01*
X71015Y-48842D01*
X72325Y-50008D01*
X73853Y-50300D01*
X75381Y-49717D01*
X76910Y-47967D01*
G01X87641Y-50300D02*
Y-38634D01*
G01Y-40967D02*
X88733Y-39800D01*
X89825Y-38925D01*
X91353Y-38634D01*
X92444Y-38925D01*
X93755Y-39800D01*
G01X125698Y-38634D02*
Y-50300D01*
G01Y-33967D02*
X125261Y-33675D01*
Y-33092D01*
X125698Y-32800D01*
X126135Y-33092D01*
Y-33675D01*
X125698Y-33967D01*
G01X139923Y-48259D02*
X141015Y-49425D01*
X142543Y-50300D01*
X143853D01*
X145163Y-49717D01*
X146036Y-48842D01*
X146473Y-47676D01*
X146255Y-45925D01*
X145381Y-45050D01*
X141451Y-43300D01*
X140578Y-41258D01*
X141015Y-39800D01*
X141888Y-38925D01*
X143198Y-38634D01*
X144508Y-38925D01*
X145818Y-39800D01*
G01X174704Y-54675D02*
X176233Y-55842D01*
X177543Y-56133D01*
X179290Y-55550D01*
X180600Y-54092D01*
X181255Y-51466D01*
Y-38634D01*
G01Y-33967D02*
X180818Y-33675D01*
Y-33092D01*
X181255Y-32800D01*
X181691Y-33092D01*
Y-33675D01*
X181255Y-33967D01*
G01X191986Y-38634D02*
Y-46800D01*
X192860Y-48842D01*
X194170Y-50008D01*
X195698Y-50300D01*
X197226Y-50008D01*
X198536Y-48842D01*
X199410Y-46800D01*
G01Y-50300D02*
Y-38634D01*
G01X209923Y-48259D02*
X211015Y-49425D01*
X212543Y-50300D01*
X213853D01*
X215163Y-49717D01*
X216036Y-48842D01*
X216473Y-47676D01*
X216255Y-45925D01*
X215381Y-45050D01*
X211451Y-43300D01*
X210578Y-41258D01*
X211015Y-39800D01*
X211888Y-38925D01*
X213198Y-38634D01*
X214508Y-38925D01*
X215818Y-39800D01*
G01X230698Y-32800D02*
Y-50300D01*
G01X227641Y-38634D02*
X233755D01*
G01X264388Y-50300D02*
Y-35425D01*
X264825Y-33967D01*
X265698Y-33092D01*
X267008Y-32800D01*
X268318Y-33383D01*
X268973Y-34842D01*
G01X266353Y-39800D02*
X261986D01*
G01X283198Y-50300D02*
X281888Y-50008D01*
X280578Y-48842D01*
X279704Y-46800D01*
X279268Y-44467D01*
X279704Y-42133D01*
X280578Y-40092D01*
X281888Y-38925D01*
X283198Y-38634D01*
X284508Y-38925D01*
X285818Y-40092D01*
X286691Y-42133D01*
X286910Y-44467D01*
X286691Y-46800D01*
X285818Y-48842D01*
X284508Y-50008D01*
X283198Y-50300D01*
G01X297641D02*
Y-38634D01*
G01Y-40967D02*
X298733Y-39800D01*
X299825Y-38925D01*
X301353Y-38634D01*
X302444Y-38925D01*
X303755Y-39800D01*
G01X331113Y-55550D02*
X332423Y-56133D01*
X334170Y-55550D01*
X335261Y-54384D01*
X336135Y-52925D01*
X337444Y-48259D01*
X340283Y-38634D01*
G01X333296D02*
X337444Y-48259D01*
G01X353198Y-50300D02*
X351888Y-50008D01*
X350578Y-48842D01*
X349704Y-46800D01*
X349268Y-44467D01*
X349704Y-42133D01*
X350578Y-40092D01*
X351888Y-38925D01*
X353198Y-38634D01*
X354508Y-38925D01*
X355818Y-40092D01*
X356691Y-42133D01*
X356910Y-44467D01*
X356691Y-46800D01*
X355818Y-48842D01*
X354508Y-50008D01*
X353198Y-50300D01*
G01X366986Y-38634D02*
Y-46800D01*
X367860Y-48842D01*
X369170Y-50008D01*
X370698Y-50300D01*
X372226Y-50008D01*
X373536Y-48842D01*
X374410Y-46800D01*
G01Y-50300D02*
Y-38634D01*
G01X385141Y-50300D02*
Y-38634D01*
G01Y-40967D02*
X386233Y-39800D01*
X387325Y-38925D01*
X388853Y-38634D01*
X389944Y-38925D01*
X391255Y-39800D01*
G01X420141Y-50300D02*
Y-38634D01*
G01Y-40967D02*
X421233Y-39800D01*
X422325Y-38925D01*
X423853Y-38634D01*
X424944Y-38925D01*
X426255Y-39800D01*
G01X437423Y-42425D02*
X444410D01*
X443755Y-40383D01*
X442663Y-39217D01*
X441135Y-38634D01*
X439606Y-38925D01*
X438296Y-39800D01*
X437423Y-41842D01*
X436986Y-43592D01*
Y-45342D01*
X437423Y-47092D01*
X438515Y-48842D01*
X439825Y-50008D01*
X441353Y-50300D01*
X442881Y-49717D01*
X444410Y-47967D01*
G01X456888Y-50300D02*
Y-35425D01*
X457325Y-33967D01*
X458198Y-33092D01*
X459508Y-32800D01*
X460818Y-33383D01*
X461473Y-34842D01*
G01X458853Y-39800D02*
X454486D01*
G01X472423Y-42425D02*
X479410D01*
X478755Y-40383D01*
X477663Y-39217D01*
X476135Y-38634D01*
X474606Y-38925D01*
X473296Y-39800D01*
X472423Y-41842D01*
X471986Y-43592D01*
Y-45342D01*
X472423Y-47092D01*
X473515Y-48842D01*
X474825Y-50008D01*
X476353Y-50300D01*
X477881Y-49717D01*
X479410Y-47967D01*
G01X490141Y-50300D02*
Y-38634D01*
G01Y-40967D02*
X491233Y-39800D01*
X492325Y-38925D01*
X493853Y-38634D01*
X494944Y-38925D01*
X496255Y-39800D01*
G01X507423Y-42425D02*
X514410D01*
X513755Y-40383D01*
X512663Y-39217D01*
X511135Y-38634D01*
X509606Y-38925D01*
X508296Y-39800D01*
X507423Y-41842D01*
X506986Y-43592D01*
Y-45342D01*
X507423Y-47092D01*
X508515Y-48842D01*
X509825Y-50008D01*
X511353Y-50300D01*
X512881Y-49717D01*
X514410Y-47967D01*
G01X524486Y-50300D02*
Y-38634D01*
G01Y-41550D02*
X525360Y-40092D01*
X526670Y-38925D01*
X528416Y-38634D01*
X529944Y-38925D01*
X531255Y-40092D01*
X531910Y-42133D01*
Y-50300D01*
G01X549191Y-40092D02*
X547663Y-38925D01*
X546353Y-38634D01*
X544606Y-39217D01*
X543296Y-40383D01*
X542423Y-42425D01*
X542204Y-44467D01*
X542423Y-46509D01*
X543296Y-48259D01*
X544606Y-49717D01*
X546353Y-50300D01*
X547881Y-49717D01*
X549191Y-48550D01*
G01X559923Y-42425D02*
X566910D01*
X566255Y-40383D01*
X565163Y-39217D01*
X563635Y-38634D01*
X562106Y-38925D01*
X560796Y-39800D01*
X559923Y-41842D01*
X559486Y-43592D01*
Y-45342D01*
X559923Y-47092D01*
X561015Y-48842D01*
X562325Y-50008D01*
X563853Y-50300D01*
X565381Y-49717D01*
X566910Y-47967D01*
G01X598198Y-32800D02*
Y-50300D01*
G01X595141Y-38634D02*
X601255D01*
G01X615698Y-50300D02*
X614388Y-50008D01*
X613078Y-48842D01*
X612204Y-46800D01*
X611768Y-44467D01*
X612204Y-42133D01*
X613078Y-40092D01*
X614388Y-38925D01*
X615698Y-38634D01*
X617008Y-38925D01*
X618318Y-40092D01*
X619191Y-42133D01*
X619410Y-44467D01*
X619191Y-46800D01*
X618318Y-48842D01*
X617008Y-50008D01*
X615698Y-50300D01*
G01X649388D02*
Y-35425D01*
X649825Y-33967D01*
X650698Y-33092D01*
X652008Y-32800D01*
X653318Y-33383D01*
X653973Y-34842D01*
G01X651353Y-39800D02*
X646986D01*
G01X668198Y-38634D02*
Y-50300D01*
G01Y-33967D02*
X667761Y-33675D01*
Y-33092D01*
X668198Y-32800D01*
X668635Y-33092D01*
Y-33675D01*
X668198Y-33967D01*
G01X681986Y-50300D02*
Y-38634D01*
G01Y-41550D02*
X682860Y-40092D01*
X684170Y-38925D01*
X685916Y-38634D01*
X687444Y-38925D01*
X688755Y-40092D01*
X689410Y-42133D01*
Y-50300D01*
G01X707128Y-32800D02*
Y-50300D01*
G01Y-47676D02*
X706255Y-49134D01*
X704944Y-50008D01*
X703416Y-50300D01*
X701670Y-49717D01*
X700360Y-48259D01*
X699486Y-46509D01*
X699268Y-44467D01*
X699486Y-42425D01*
X700360Y-40675D01*
X701670Y-39217D01*
X703416Y-38634D01*
X704944Y-38925D01*
X706036Y-39509D01*
X707128Y-40675D01*
G01X738198Y-32800D02*
Y-50300D01*
G01X735141Y-38634D02*
X741255D01*
G01X751986Y-50300D02*
Y-32800D01*
G01Y-41258D02*
X753078Y-39800D01*
X754170Y-38925D01*
X755916Y-38634D01*
X757226Y-38925D01*
X758755Y-40092D01*
X759410Y-41842D01*
Y-50300D01*
G01X769923Y-42425D02*
X776910D01*
X776255Y-40383D01*
X775163Y-39217D01*
X773635Y-38634D01*
X772106Y-38925D01*
X770796Y-39800D01*
X769923Y-41842D01*
X769486Y-43592D01*
Y-45342D01*
X769923Y-47092D01*
X771015Y-48842D01*
X772325Y-50008D01*
X773853Y-50300D01*
X775381Y-49717D01*
X776910Y-47967D01*
G01X803395Y-50300D02*
Y-32800D01*
X807761D01*
X809508Y-33675D01*
X810818Y-34842D01*
X811910Y-36591D01*
X812783Y-38634D01*
X813001Y-41550D01*
X812783Y-44467D01*
X811910Y-46509D01*
X810818Y-48259D01*
X809508Y-49425D01*
X807761Y-50300D01*
X803395D01*
G01X821331D02*
Y-32800D01*
X826571D01*
X828318Y-33675D01*
X829628Y-35717D01*
X830065Y-38050D01*
X829628Y-40383D01*
X828536Y-42133D01*
X826571Y-43009D01*
X821331D01*
G01X860698Y-38634D02*
Y-50300D01*
G01Y-33967D02*
X860261Y-33675D01*
Y-33092D01*
X860698Y-32800D01*
X861135Y-33092D01*
Y-33675D01*
X860698Y-33967D01*
G01X871648Y-50300D02*
Y-38634D01*
G01Y-41842D02*
X872303Y-40383D01*
X873395Y-39217D01*
X874923Y-38634D01*
X876451Y-39217D01*
X877543Y-40383D01*
X878198Y-41842D01*
Y-50300D01*
G01Y-41842D02*
X878853Y-40383D01*
X879944Y-39217D01*
X881473Y-38634D01*
X883001Y-39217D01*
X884093Y-40383D01*
X884748Y-42133D01*
Y-50300D01*
G01X891768Y-56133D02*
Y-38634D01*
G01Y-41258D02*
X892860Y-39800D01*
X893951Y-38925D01*
X895698Y-38634D01*
X897226Y-38925D01*
X898755Y-40383D01*
X899410Y-42425D01*
X899628Y-44467D01*
X899410Y-46509D01*
X898755Y-48550D01*
X897444Y-49717D01*
X895698Y-50300D01*
X894170Y-50008D01*
X892641Y-49134D01*
X891768Y-47967D01*
G01X909923Y-42425D02*
X916910D01*
X916255Y-40383D01*
X915163Y-39217D01*
X913635Y-38634D01*
X912106Y-38925D01*
X910796Y-39800D01*
X909923Y-41842D01*
X909486Y-43592D01*
Y-45342D01*
X909923Y-47092D01*
X911015Y-48842D01*
X912325Y-50008D01*
X913853Y-50300D01*
X915381Y-49717D01*
X916910Y-47967D01*
G01X934628Y-32800D02*
Y-50300D01*
G01Y-47676D02*
X933755Y-49134D01*
X932444Y-50008D01*
X930916Y-50300D01*
X929170Y-49717D01*
X927860Y-48259D01*
X926986Y-46509D01*
X926768Y-44467D01*
X926986Y-42425D01*
X927860Y-40675D01*
X929170Y-39217D01*
X930916Y-38634D01*
X932444Y-38925D01*
X933536Y-39509D01*
X934628Y-40675D01*
G01X952128Y-50300D02*
Y-38634D01*
G01Y-40675D02*
X951255Y-39509D01*
X949944Y-38925D01*
X948416Y-38634D01*
X946888Y-39217D01*
X945578Y-40383D01*
X944704Y-42133D01*
X944268Y-44467D01*
X944704Y-46800D01*
X945578Y-48550D01*
X946888Y-49717D01*
X948416Y-50300D01*
X949944Y-50008D01*
X951255Y-49134D01*
X952128Y-47967D01*
G01X961986Y-50300D02*
Y-38634D01*
G01Y-41550D02*
X962860Y-40092D01*
X964170Y-38925D01*
X965916Y-38634D01*
X967444Y-38925D01*
X968755Y-40092D01*
X969410Y-42133D01*
Y-50300D01*
G01X986691Y-40092D02*
X985163Y-38925D01*
X983853Y-38634D01*
X982106Y-39217D01*
X980796Y-40383D01*
X979923Y-42425D01*
X979704Y-44467D01*
X979923Y-46509D01*
X980796Y-48259D01*
X982106Y-49717D01*
X983853Y-50300D01*
X985381Y-49717D01*
X986691Y-48550D01*
G01X997423Y-42425D02*
X1004410D01*
X1003755Y-40383D01*
X1002663Y-39217D01*
X1001135Y-38634D01*
X999606Y-38925D01*
X998296Y-39800D01*
X997423Y-41842D01*
X996986Y-43592D01*
Y-45342D01*
X997423Y-47092D01*
X998515Y-48842D01*
X999825Y-50008D01*
X1001353Y-50300D01*
X1002881Y-49717D01*
X1004410Y-47967D01*
G01X1035698Y-32800D02*
Y-50300D01*
G01X1032641Y-38634D02*
X1038755D01*
G01X1050141Y-50300D02*
Y-38634D01*
G01Y-40967D02*
X1051233Y-39800D01*
X1052325Y-38925D01*
X1053853Y-38634D01*
X1054944Y-38925D01*
X1056255Y-39800D01*
G01X1074628Y-50300D02*
Y-38634D01*
G01Y-40675D02*
X1073755Y-39509D01*
X1072444Y-38925D01*
X1070916Y-38634D01*
X1069388Y-39217D01*
X1068078Y-40383D01*
X1067204Y-42133D01*
X1066768Y-44467D01*
X1067204Y-46800D01*
X1068078Y-48550D01*
X1069388Y-49717D01*
X1070916Y-50300D01*
X1072444Y-50008D01*
X1073755Y-49134D01*
X1074628Y-47967D01*
G01X1091691Y-40092D02*
X1090163Y-38925D01*
X1088853Y-38634D01*
X1087106Y-39217D01*
X1085796Y-40383D01*
X1084923Y-42425D01*
X1084704Y-44467D01*
X1084923Y-46509D01*
X1085796Y-48259D01*
X1087106Y-49717D01*
X1088853Y-50300D01*
X1090381Y-49717D01*
X1091691Y-48550D01*
G01X1102423Y-42425D02*
X1109410D01*
X1108755Y-40383D01*
X1107663Y-39217D01*
X1106135Y-38634D01*
X1104606Y-38925D01*
X1103296Y-39800D01*
X1102423Y-41842D01*
X1101986Y-43592D01*
Y-45342D01*
X1102423Y-47092D01*
X1103515Y-48842D01*
X1104825Y-50008D01*
X1106353Y-50300D01*
X1107881Y-49717D01*
X1109410Y-47967D01*
G01X1119923Y-48259D02*
X1121015Y-49425D01*
X1122543Y-50300D01*
X1123853D01*
X1125163Y-49717D01*
X1126036Y-48842D01*
X1126473Y-47676D01*
X1126255Y-45925D01*
X1125381Y-45050D01*
X1121451Y-43300D01*
X1120578Y-41258D01*
X1121015Y-39800D01*
X1121888Y-38925D01*
X1123198Y-38634D01*
X1124508Y-38925D01*
X1125818Y-39800D01*
G01X1158198Y-38634D02*
Y-50300D01*
G01Y-33967D02*
X1157761Y-33675D01*
Y-33092D01*
X1158198Y-32800D01*
X1158635Y-33092D01*
Y-33675D01*
X1158198Y-33967D01*
G01X1171986Y-50300D02*
Y-38634D01*
G01Y-41550D02*
X1172860Y-40092D01*
X1174170Y-38925D01*
X1175916Y-38634D01*
X1177444Y-38925D01*
X1178755Y-40092D01*
X1179410Y-42133D01*
Y-50300D01*
G01X1210698D02*
Y-32800D01*
G01X1232128Y-50300D02*
Y-38634D01*
G01Y-40675D02*
X1231255Y-39509D01*
X1229944Y-38925D01*
X1228416Y-38634D01*
X1226888Y-39217D01*
X1225578Y-40383D01*
X1224704Y-42133D01*
X1224268Y-44467D01*
X1224704Y-46800D01*
X1225578Y-48550D01*
X1226888Y-49717D01*
X1228416Y-50300D01*
X1229944Y-50008D01*
X1231255Y-49134D01*
X1232128Y-47967D01*
G01X1241113Y-55550D02*
X1242423Y-56133D01*
X1244170Y-55550D01*
X1245261Y-54384D01*
X1246135Y-52925D01*
X1247444Y-48259D01*
X1250283Y-38634D01*
G01X1243296D02*
X1247444Y-48259D01*
G01X1259923Y-42425D02*
X1266910D01*
X1266255Y-40383D01*
X1265163Y-39217D01*
X1263635Y-38634D01*
X1262106Y-38925D01*
X1260796Y-39800D01*
X1259923Y-41842D01*
X1259486Y-43592D01*
Y-45342D01*
X1259923Y-47092D01*
X1261015Y-48842D01*
X1262325Y-50008D01*
X1263853Y-50300D01*
X1265381Y-49717D01*
X1266910Y-47967D01*
G01X1277641Y-50300D02*
Y-38634D01*
G01Y-40967D02*
X1278733Y-39800D01*
X1279825Y-38925D01*
X1281353Y-38634D01*
X1282444Y-38925D01*
X1283755Y-39800D01*
G01X1311331Y-32800D02*
Y-50300D01*
X1320065D01*
G01X1328395Y-46800D02*
X1329704Y-48842D01*
X1331451Y-50008D01*
X1333416Y-50300D01*
X1335163Y-50008D01*
X1336910Y-48550D01*
X1338001Y-46800D01*
X1338220Y-45050D01*
X1337783Y-43009D01*
X1336255Y-41550D01*
X1334726Y-40967D01*
X1332761D01*
G01X1334726D02*
X1336036Y-40092D01*
X1337128Y-38634D01*
X1337565Y-36884D01*
X1337128Y-35133D01*
X1336036Y-33675D01*
X1334071Y-32800D01*
X1332106Y-33092D01*
X1330141Y-34259D01*
G01X1350698Y-50883D02*
X1350261Y-50592D01*
Y-50008D01*
X1350698Y-49717D01*
X1351135Y-50008D01*
Y-50592D01*
X1350698Y-50883D01*
G01X1201883Y1950376D02*
X1207123D01*
G01X1204503D02*
Y1932876D01*
G01X1201883D02*
X1207123D01*
G01X1216326D02*
Y1950376D01*
X1222003Y1935793D01*
X1227680Y1950376D01*
Y1932876D01*
G01X1235136D02*
Y1950376D01*
X1240376D01*
X1242123Y1949501D01*
X1243433Y1947459D01*
X1243870Y1945126D01*
X1243433Y1942793D01*
X1242341Y1941043D01*
X1240376Y1940167D01*
X1235136D01*
G01X1255911Y1927043D02*
X1253728Y1929959D01*
X1252636Y1932876D01*
Y1944542D01*
X1253728Y1947459D01*
X1255911Y1950376D01*
G01X1274503Y1932876D02*
X1272756Y1933168D01*
X1271228Y1934334D01*
X1269918Y1936084D01*
X1269044Y1938126D01*
X1268608Y1940459D01*
Y1942793D01*
X1269044Y1945126D01*
X1269918Y1947168D01*
X1271228Y1948917D01*
X1272756Y1950084D01*
X1274503Y1950376D01*
X1276249Y1950084D01*
X1277778Y1948917D01*
X1279088Y1947168D01*
X1279962Y1945126D01*
X1280398Y1942793D01*
Y1940459D01*
X1279962Y1938126D01*
X1279088Y1936084D01*
X1277778Y1934334D01*
X1276249Y1933168D01*
X1274503Y1932876D01*
G01X1288291D02*
Y1950376D01*
G01Y1941918D02*
X1289383Y1943376D01*
X1290475Y1944251D01*
X1292221Y1944542D01*
X1293531Y1944251D01*
X1295060Y1943084D01*
X1295715Y1941334D01*
Y1932876D01*
G01X1302953D02*
Y1944542D01*
G01Y1941334D02*
X1303608Y1942793D01*
X1304700Y1943959D01*
X1306228Y1944542D01*
X1307756Y1943959D01*
X1308848Y1942793D01*
X1309503Y1941334D01*
Y1932876D01*
G01Y1941334D02*
X1310158Y1942793D01*
X1311249Y1943959D01*
X1312778Y1944542D01*
X1314306Y1943959D01*
X1315398Y1942793D01*
X1316053Y1941043D01*
Y1932876D01*
G01X1328095Y1927043D02*
X1330278Y1929959D01*
X1331370Y1932876D01*
Y1944542D01*
X1330278Y1947459D01*
X1328095Y1950376D01*
G01X1180000Y1967526D02*
Y1985026D01*
X1184366D01*
X1186113Y1984151D01*
X1187423Y1982984D01*
X1188515Y1981235D01*
X1189388Y1979192D01*
X1189606Y1976276D01*
X1189388Y1973359D01*
X1188515Y1971317D01*
X1187423Y1969567D01*
X1186113Y1968401D01*
X1184366Y1967526D01*
X1180000D01*
G01X1197936D02*
Y1985026D01*
X1203176D01*
X1204923Y1984151D01*
X1206233Y1982109D01*
X1206670Y1979776D01*
X1206233Y1977443D01*
X1205141Y1975693D01*
X1203176Y1974817D01*
X1197936D01*
G01X1234683Y1985026D02*
X1239923D01*
G01X1237303D02*
Y1967526D01*
G01X1234683D02*
X1239923D01*
G01X1249126D02*
Y1985026D01*
X1254803Y1970443D01*
X1260480Y1985026D01*
Y1967526D01*
G01X1267936D02*
Y1985026D01*
X1273176D01*
X1274923Y1984151D01*
X1276233Y1982109D01*
X1276670Y1979776D01*
X1276233Y1977443D01*
X1275141Y1975693D01*
X1273176Y1974817D01*
X1267936D01*
G01X1294170Y1967526D02*
X1285436D01*
Y1985026D01*
X1294170D01*
G01X1290676Y1976568D02*
X1285436D01*
G01X1302500Y1967526D02*
Y1985026D01*
X1306866D01*
X1308613Y1984151D01*
X1309923Y1982984D01*
X1311015Y1981235D01*
X1311888Y1979192D01*
X1312106Y1976276D01*
X1311888Y1973359D01*
X1311015Y1971317D01*
X1309923Y1969567D01*
X1308613Y1968401D01*
X1306866Y1967526D01*
X1302500D01*
G01X1319344D02*
X1324803Y1985026D01*
X1330262Y1967526D01*
G01X1328296Y1973651D02*
X1321309D01*
G01X1337281Y1967526D02*
Y1985026D01*
X1347325Y1967526D01*
Y1985026D01*
G01X1364606Y1983567D02*
X1363296Y1984443D01*
X1361768Y1985026D01*
X1360021D01*
X1358056Y1984151D01*
X1356528Y1982693D01*
X1355436Y1980942D01*
X1354563Y1978026D01*
X1354344Y1975401D01*
X1354781Y1972776D01*
X1355436Y1971026D01*
X1356746Y1969276D01*
X1358275Y1968109D01*
X1359803Y1967526D01*
X1361331D01*
X1362860Y1968109D01*
X1364170Y1968984D01*
X1365262Y1970150D01*
G01X1381670Y1967526D02*
X1372936D01*
Y1985026D01*
X1381670D01*
G01X1378176Y1976568D02*
X1372936D01*
G01X1412303Y1985026D02*
Y1967526D01*
G01X1407281Y1985026D02*
X1417325D01*
G01X1424344Y1967526D02*
X1429803Y1985026D01*
X1435262Y1967526D01*
G01X1433296Y1973651D02*
X1426309D01*
G01X1449049Y1976859D02*
X1449923Y1977734D01*
X1450578Y1979192D01*
X1451015Y1981235D01*
X1450578Y1982984D01*
X1449705Y1984151D01*
X1448176Y1985026D01*
X1442281D01*
Y1967526D01*
X1449486D01*
X1451015Y1968692D01*
X1451888Y1970443D01*
X1452325Y1972484D01*
X1451888Y1974526D01*
X1450578Y1976276D01*
X1449049Y1976859D01*
X1442281D01*
G01X1460436Y1985026D02*
Y1967526D01*
X1469170D01*
G01X1486670D02*
X1477936D01*
Y1985026D01*
X1486670D01*
G01X1483176Y1976568D02*
X1477936D01*
G01X1499803Y1966943D02*
X1499366Y1967234D01*
Y1967818D01*
X1499803Y1968109D01*
X1500240Y1967818D01*
Y1967234D01*
X1499803Y1966943D01*
G01Y1974817D02*
X1499366Y1975109D01*
Y1975693D01*
X1499803Y1975984D01*
X1500240Y1975693D01*
Y1975109D01*
X1499803Y1974817D01*
G01X1530436Y1985026D02*
Y1967526D01*
X1539170D01*
G01X1547500Y1971026D02*
X1548809Y1968984D01*
X1550556Y1967818D01*
X1552521Y1967526D01*
X1554268Y1967818D01*
X1556015Y1969276D01*
X1557106Y1971026D01*
X1557325Y1972776D01*
X1556888Y1974817D01*
X1555360Y1976276D01*
X1553831Y1976859D01*
X1551866D01*
G01X1553831D02*
X1555141Y1977734D01*
X1556233Y1979192D01*
X1556670Y1980942D01*
X1556233Y1982693D01*
X1555141Y1984151D01*
X1553176Y1985026D01*
X1551211Y1984734D01*
X1549246Y1983567D01*
G01X1217200Y1862993D02*
X1226806Y1875826D01*
G01X1222003Y1878159D02*
Y1860659D01*
G01X1226806Y1862993D02*
X1217200Y1875826D01*
G01X1215453Y1869409D02*
X1228553D01*
G01X1239503Y1863576D02*
Y1881076D01*
X1236883Y1877576D01*
G01Y1863576D02*
X1242123D01*
G01X1257003Y1881076D02*
X1255256Y1880493D01*
X1253946Y1879034D01*
X1253073Y1877285D01*
X1252418Y1874951D01*
X1252200Y1872326D01*
X1252418Y1869701D01*
X1253073Y1867367D01*
X1253946Y1865617D01*
X1255256Y1864159D01*
X1257003Y1863576D01*
X1258749Y1864159D01*
X1260060Y1865617D01*
X1260933Y1867367D01*
X1261588Y1869701D01*
X1261806Y1872326D01*
X1261588Y1874951D01*
X1260933Y1877285D01*
X1260060Y1879034D01*
X1258749Y1880493D01*
X1257003Y1881076D01*
G01X1274503D02*
X1272756Y1880493D01*
X1271446Y1879034D01*
X1270573Y1877285D01*
X1269918Y1874951D01*
X1269700Y1872326D01*
X1269918Y1869701D01*
X1270573Y1867367D01*
X1271446Y1865617D01*
X1272756Y1864159D01*
X1274503Y1863576D01*
X1276249Y1864159D01*
X1277560Y1865617D01*
X1278433Y1867367D01*
X1279088Y1869701D01*
X1279306Y1872326D01*
X1279088Y1874951D01*
X1278433Y1877285D01*
X1277560Y1879034D01*
X1276249Y1880493D01*
X1274503Y1881076D01*
G01X1292003Y1862993D02*
X1291566Y1863284D01*
Y1863868D01*
X1292003Y1864159D01*
X1292440Y1863868D01*
Y1863284D01*
X1292003Y1862993D01*
G01X1309503Y1881076D02*
X1307756Y1880493D01*
X1306446Y1879034D01*
X1305573Y1877285D01*
X1304918Y1874951D01*
X1304700Y1872326D01*
X1304918Y1869701D01*
X1305573Y1867367D01*
X1306446Y1865617D01*
X1307756Y1864159D01*
X1309503Y1863576D01*
X1311249Y1864159D01*
X1312560Y1865617D01*
X1313433Y1867367D01*
X1314088Y1869701D01*
X1314306Y1872326D01*
X1314088Y1874951D01*
X1313433Y1877285D01*
X1312560Y1879034D01*
X1311249Y1880493D01*
X1309503Y1881076D01*
G01X1239503Y1898226D02*
X1241031Y1898518D01*
X1242778Y1899392D01*
X1243870Y1900850D01*
X1244306Y1902893D01*
X1243870Y1904934D01*
X1242560Y1906684D01*
X1240595Y1907559D01*
X1238411D01*
X1237101Y1908143D01*
X1236009Y1909601D01*
X1235573Y1911642D01*
X1236228Y1913684D01*
X1237756Y1915143D01*
X1239503Y1915726D01*
X1241249Y1915143D01*
X1242778Y1913684D01*
X1243433Y1911642D01*
X1242996Y1909601D01*
X1241905Y1908143D01*
X1240595Y1907559D01*
X1238411D01*
X1236446Y1906684D01*
X1235136Y1904934D01*
X1234700Y1902893D01*
X1235136Y1900850D01*
X1236228Y1899392D01*
X1237975Y1898518D01*
X1239503Y1898226D01*
G01X1252200Y1900850D02*
X1253509Y1899392D01*
X1255038Y1898518D01*
X1257003Y1898226D01*
X1258968Y1898809D01*
X1260496Y1899976D01*
X1261588Y1902017D01*
X1261806Y1904351D01*
X1261370Y1906684D01*
X1260278Y1908143D01*
X1258749Y1909309D01*
X1257221Y1909601D01*
X1255693Y1909309D01*
X1253728Y1908143D01*
X1254383Y1915726D01*
X1260278D01*
G01X1274503Y1897643D02*
X1274066Y1897934D01*
Y1898518D01*
X1274503Y1898809D01*
X1274940Y1898518D01*
Y1897934D01*
X1274503Y1897643D01*
G01X1292003Y1915726D02*
X1290256Y1915143D01*
X1288946Y1913684D01*
X1288073Y1911935D01*
X1287418Y1909601D01*
X1287200Y1906976D01*
X1287418Y1904351D01*
X1288073Y1902017D01*
X1288946Y1900267D01*
X1290256Y1898809D01*
X1292003Y1898226D01*
X1293749Y1898809D01*
X1295060Y1900267D01*
X1295933Y1902017D01*
X1296588Y1904351D01*
X1296806Y1906976D01*
X1296588Y1909601D01*
X1295933Y1911935D01*
X1295060Y1913684D01*
X1293749Y1915143D01*
X1292003Y1915726D01*
G01X1407953Y1950376D02*
X1411009Y1932876D01*
X1414503Y1950376D01*
X1417996Y1932876D01*
X1421053Y1950376D01*
G01X1429383D02*
X1434623D01*
G01X1432003D02*
Y1932876D01*
G01X1429383D02*
X1434623D01*
G01X1444700D02*
Y1950376D01*
X1449066D01*
X1450813Y1949501D01*
X1452123Y1948334D01*
X1453215Y1946585D01*
X1454088Y1944542D01*
X1454306Y1941626D01*
X1454088Y1938709D01*
X1453215Y1936667D01*
X1452123Y1934917D01*
X1450813Y1933751D01*
X1449066Y1932876D01*
X1444700D01*
G01X1467003Y1950376D02*
Y1932876D01*
G01X1461981Y1950376D02*
X1472025D01*
G01X1479918Y1932876D02*
Y1950376D01*
G01X1489088D02*
Y1932876D01*
G01Y1941626D02*
X1479918D01*
G01X1500911Y1927043D02*
X1498728Y1929959D01*
X1497636Y1932876D01*
Y1944542D01*
X1498728Y1947459D01*
X1500911Y1950376D01*
G01X1512953Y1932876D02*
Y1944542D01*
G01Y1941334D02*
X1513608Y1942793D01*
X1514700Y1943959D01*
X1516228Y1944542D01*
X1517756Y1943959D01*
X1518848Y1942793D01*
X1519503Y1941334D01*
Y1932876D01*
G01Y1941334D02*
X1520158Y1942793D01*
X1521249Y1943959D01*
X1522778Y1944542D01*
X1524306Y1943959D01*
X1525398Y1942793D01*
X1526053Y1941043D01*
Y1932876D01*
G01X1537003Y1944542D02*
Y1932876D01*
G01Y1949209D02*
X1536566Y1949501D01*
Y1950084D01*
X1537003Y1950376D01*
X1537440Y1950084D01*
Y1949501D01*
X1537003Y1949209D01*
G01X1554503Y1932876D02*
Y1950376D01*
G01X1568728Y1934917D02*
X1569820Y1933751D01*
X1571348Y1932876D01*
X1572658D01*
X1573968Y1933459D01*
X1574841Y1934334D01*
X1575278Y1935500D01*
X1575060Y1937251D01*
X1574186Y1938126D01*
X1570256Y1939876D01*
X1569383Y1941918D01*
X1569820Y1943376D01*
X1570693Y1944251D01*
X1572003Y1944542D01*
X1573313Y1944251D01*
X1574623Y1943376D01*
G01X1590595Y1927043D02*
X1592778Y1929959D01*
X1593870Y1932876D01*
Y1944542D01*
X1592778Y1947459D01*
X1590595Y1950376D01*
G01X1452123Y1863576D02*
Y1881076D01*
X1444044Y1868534D01*
X1454962D01*
G01X1467003Y1862993D02*
X1466566Y1863284D01*
Y1863868D01*
X1467003Y1864159D01*
X1467440Y1863868D01*
Y1863284D01*
X1467003Y1862993D01*
G01X1479700Y1866200D02*
X1481009Y1864742D01*
X1482538Y1863868D01*
X1484503Y1863576D01*
X1486468Y1864159D01*
X1487996Y1865326D01*
X1489088Y1867367D01*
X1489306Y1869701D01*
X1488870Y1872034D01*
X1487778Y1873493D01*
X1486249Y1874659D01*
X1484721Y1874951D01*
X1483193Y1874659D01*
X1481228Y1873493D01*
X1481883Y1881076D01*
X1487778D01*
G01X1498073Y1862993D02*
X1505933Y1881076D01*
G01X1515791Y1865617D02*
X1517320Y1864159D01*
X1519066Y1863576D01*
X1520813Y1864159D01*
X1522341Y1865909D01*
X1523433Y1868534D01*
X1523870Y1871159D01*
Y1874367D01*
X1523433Y1876992D01*
X1522341Y1879326D01*
X1521031Y1880493D01*
X1519503Y1881076D01*
X1517756Y1880493D01*
X1516446Y1879326D01*
X1515573Y1877576D01*
X1515136Y1875242D01*
X1515573Y1873201D01*
X1516665Y1871159D01*
X1517975Y1869992D01*
X1519503Y1869701D01*
X1521249Y1870284D01*
X1522560Y1871743D01*
X1523870Y1874367D01*
G01X1537003Y1862993D02*
X1536566Y1863284D01*
Y1863868D01*
X1537003Y1864159D01*
X1537440Y1863868D01*
Y1863284D01*
X1537003Y1862993D01*
G01X1554503Y1881076D02*
X1552756Y1880493D01*
X1551446Y1879034D01*
X1550573Y1877285D01*
X1549918Y1874951D01*
X1549700Y1872326D01*
X1549918Y1869701D01*
X1550573Y1867367D01*
X1551446Y1865617D01*
X1552756Y1864159D01*
X1554503Y1863576D01*
X1556249Y1864159D01*
X1557560Y1865617D01*
X1558433Y1867367D01*
X1559088Y1869701D01*
X1559306Y1872326D01*
X1559088Y1874951D01*
X1558433Y1877285D01*
X1557560Y1879034D01*
X1556249Y1880493D01*
X1554503Y1881076D01*
G01X1445355Y1905517D02*
X1446883Y1907559D01*
X1448193Y1908726D01*
X1449940Y1909309D01*
X1451468Y1908726D01*
X1452560Y1907559D01*
X1453433Y1905809D01*
X1453651Y1903768D01*
X1453433Y1902017D01*
X1452560Y1900267D01*
X1451249Y1898809D01*
X1449721Y1898226D01*
X1447975Y1898809D01*
X1446446Y1900559D01*
X1445573Y1903184D01*
X1445355Y1906101D01*
X1445791Y1909892D01*
X1446446Y1911935D01*
X1447538Y1913976D01*
X1449066Y1915434D01*
X1450595Y1915726D01*
X1452123Y1915143D01*
X1453215Y1913684D01*
G01X1467003Y1897643D02*
X1466566Y1897934D01*
Y1898518D01*
X1467003Y1898809D01*
X1467440Y1898518D01*
Y1897934D01*
X1467003Y1897643D01*
G01X1479700Y1900850D02*
X1481009Y1899392D01*
X1482538Y1898518D01*
X1484503Y1898226D01*
X1486468Y1898809D01*
X1487996Y1899976D01*
X1489088Y1902017D01*
X1489306Y1904351D01*
X1488870Y1906684D01*
X1487778Y1908143D01*
X1486249Y1909309D01*
X1484721Y1909601D01*
X1483193Y1909309D01*
X1481228Y1908143D01*
X1481883Y1915726D01*
X1487778D01*
G01X1498073Y1897643D02*
X1505933Y1915726D01*
G01X1519066Y1898226D02*
X1519503Y1902017D01*
X1520158Y1905226D01*
X1521031Y1908143D01*
X1522123Y1911351D01*
X1523870Y1915726D01*
X1515136D01*
G01X1537003Y1897643D02*
X1536566Y1897934D01*
Y1898518D01*
X1537003Y1898809D01*
X1537440Y1898518D01*
Y1897934D01*
X1537003Y1897643D01*
G01X1549700Y1900850D02*
X1551009Y1899392D01*
X1552538Y1898518D01*
X1554503Y1898226D01*
X1556468Y1898809D01*
X1557996Y1899976D01*
X1559088Y1902017D01*
X1559306Y1904351D01*
X1558870Y1906684D01*
X1557778Y1908143D01*
X1556249Y1909309D01*
X1554721Y1909601D01*
X1553193Y1909309D01*
X1551228Y1908143D01*
X1551883Y1915726D01*
X1557778D01*
G01X1689700Y1863576D02*
Y1881076D01*
X1694066D01*
X1695813Y1880201D01*
X1697123Y1879034D01*
X1698215Y1877285D01*
X1699088Y1875242D01*
X1699306Y1872326D01*
X1699088Y1869409D01*
X1698215Y1867367D01*
X1697123Y1865617D01*
X1695813Y1864451D01*
X1694066Y1863576D01*
X1689700D01*
G01X1707636D02*
Y1881076D01*
X1712876D01*
X1714623Y1880201D01*
X1715933Y1878159D01*
X1716370Y1875826D01*
X1715933Y1873493D01*
X1714841Y1871743D01*
X1712876Y1870867D01*
X1707636D01*
G01X1677003Y1950376D02*
Y1932876D01*
G01X1671981Y1950376D02*
X1682025D01*
G01X1694503Y1932876D02*
Y1940751D01*
X1690136Y1950376D01*
G01X1698870D02*
X1694503Y1940751D01*
G01X1707636Y1932876D02*
Y1950376D01*
X1712876D01*
X1714623Y1949501D01*
X1715933Y1947459D01*
X1716370Y1945126D01*
X1715933Y1942793D01*
X1714841Y1941043D01*
X1712876Y1940167D01*
X1707636D01*
G01X1733870Y1932876D02*
X1725136D01*
Y1950376D01*
X1733870D01*
G01X1730376Y1941918D02*
X1725136D01*
G01X1689700Y1898226D02*
Y1915726D01*
X1694066D01*
X1695813Y1914851D01*
X1697123Y1913684D01*
X1698215Y1911935D01*
X1699088Y1909892D01*
X1699306Y1906976D01*
X1699088Y1904059D01*
X1698215Y1902017D01*
X1697123Y1900267D01*
X1695813Y1899101D01*
X1694066Y1898226D01*
X1689700D01*
G01X1707636D02*
Y1915726D01*
X1712876D01*
X1714623Y1914851D01*
X1715933Y1912809D01*
X1716370Y1910476D01*
X1715933Y1908143D01*
X1714841Y1906393D01*
X1712876Y1905517D01*
X1707636D01*
G01X1777636Y1932876D02*
Y1950376D01*
X1783095D01*
X1784841Y1949501D01*
X1785933Y1948334D01*
X1786370Y1946001D01*
X1785933Y1943667D01*
X1784623Y1942209D01*
X1783095Y1941334D01*
X1777636D01*
G01X1783095D02*
X1786370Y1932876D01*
G01X1796228Y1940751D02*
X1803215D01*
X1802560Y1942793D01*
X1801468Y1943959D01*
X1799940Y1944542D01*
X1798411Y1944251D01*
X1797101Y1943376D01*
X1796228Y1941334D01*
X1795791Y1939584D01*
Y1937834D01*
X1796228Y1936084D01*
X1797320Y1934334D01*
X1798630Y1933168D01*
X1800158Y1932876D01*
X1801686Y1933459D01*
X1803215Y1935209D01*
G01X1815693Y1932876D02*
Y1947751D01*
X1816130Y1949209D01*
X1817003Y1950084D01*
X1818313Y1950376D01*
X1819623Y1949793D01*
X1820278Y1948334D01*
G01X1817658Y1943376D02*
X1813291D01*
G01X1834503Y1932293D02*
X1834066Y1932584D01*
Y1933168D01*
X1834503Y1933459D01*
X1834940Y1933168D01*
Y1932584D01*
X1834503Y1932293D01*
G01X1865136Y1932876D02*
Y1950376D01*
X1870376D01*
X1872123Y1949501D01*
X1873433Y1947459D01*
X1873870Y1945126D01*
X1873433Y1942793D01*
X1872341Y1941043D01*
X1870376Y1940167D01*
X1865136D01*
G01X1887003Y1932876D02*
Y1950376D01*
G01X1908433Y1932876D02*
Y1944542D01*
G01Y1942501D02*
X1907560Y1943667D01*
X1906249Y1944251D01*
X1904721Y1944542D01*
X1903193Y1943959D01*
X1901883Y1942793D01*
X1901009Y1941043D01*
X1900573Y1938709D01*
X1901009Y1936376D01*
X1901883Y1934626D01*
X1903193Y1933459D01*
X1904721Y1932876D01*
X1906249Y1933168D01*
X1907560Y1934042D01*
X1908433Y1935209D01*
G01X1918291Y1932876D02*
Y1944542D01*
G01Y1941626D02*
X1919165Y1943084D01*
X1920475Y1944251D01*
X1922221Y1944542D01*
X1923749Y1944251D01*
X1925060Y1943084D01*
X1925715Y1941043D01*
Y1932876D01*
G01X1936228Y1940751D02*
X1943215D01*
X1942560Y1942793D01*
X1941468Y1943959D01*
X1939940Y1944542D01*
X1938411Y1944251D01*
X1937101Y1943376D01*
X1936228Y1941334D01*
X1935791Y1939584D01*
Y1937834D01*
X1936228Y1936084D01*
X1937320Y1934334D01*
X1938630Y1933168D01*
X1940158Y1932876D01*
X1941686Y1933459D01*
X1943215Y1935209D01*
G01X1821386Y1881076D02*
Y1863576D01*
X1830120D01*
G01X1839105Y1878159D02*
X1840415Y1879909D01*
X1841943Y1880784D01*
X1843690Y1881076D01*
X1845873Y1880493D01*
X1847401Y1879034D01*
X1847838Y1877285D01*
X1847620Y1875534D01*
X1846746Y1874076D01*
X1842380Y1871159D01*
X1840415Y1869118D01*
X1839105Y1866200D01*
X1838668Y1863576D01*
X1847838D01*
G01X1856823Y1862993D02*
X1864683Y1881076D01*
G01X1873886D02*
Y1863576D01*
X1882620D01*
G01X1898373D02*
Y1881076D01*
X1890294Y1868534D01*
X1901212D01*
G01X1821386Y1915726D02*
Y1898226D01*
X1830120D01*
G01X1839105Y1912809D02*
X1840415Y1914559D01*
X1841943Y1915434D01*
X1843690Y1915726D01*
X1845873Y1915143D01*
X1847401Y1913684D01*
X1847838Y1911935D01*
X1847620Y1910184D01*
X1846746Y1908726D01*
X1842380Y1905809D01*
X1840415Y1903768D01*
X1839105Y1900850D01*
X1838668Y1898226D01*
X1847838D01*
G01X1856823Y1897643D02*
X1864683Y1915726D01*
G01X1873886D02*
Y1898226D01*
X1882620D01*
G01X1898373D02*
Y1915726D01*
X1890294Y1903184D01*
X1901212D01*
G01X1982500Y1932293D02*
X1992106Y1945126D01*
G01X1987303Y1947459D02*
Y1929959D01*
G01X1992106Y1932293D02*
X1982500Y1945126D01*
G01X1980753Y1938709D02*
X1993853D01*
G01X2019465D02*
X2025141D01*
G01X2052500Y1932876D02*
Y1950376D01*
X2056866D01*
X2058613Y1949501D01*
X2059923Y1948334D01*
X2061015Y1946585D01*
X2061888Y1944542D01*
X2062106Y1941626D01*
X2061888Y1938709D01*
X2061015Y1936667D01*
X2059923Y1934917D01*
X2058613Y1933751D01*
X2056866Y1932876D01*
X2052500D01*
G01X2071528Y1940751D02*
X2078515D01*
X2077860Y1942793D01*
X2076768Y1943959D01*
X2075240Y1944542D01*
X2073711Y1944251D01*
X2072401Y1943376D01*
X2071528Y1941334D01*
X2071091Y1939584D01*
Y1937834D01*
X2071528Y1936084D01*
X2072620Y1934334D01*
X2073930Y1933168D01*
X2075458Y1932876D01*
X2076986Y1933459D01*
X2078515Y1935209D01*
G01X2088591Y1932876D02*
Y1944542D01*
G01Y1941626D02*
X2089465Y1943084D01*
X2090775Y1944251D01*
X2092521Y1944542D01*
X2094049Y1944251D01*
X2095360Y1943084D01*
X2096015Y1941043D01*
Y1932876D01*
G01X2109803D02*
X2108493Y1933168D01*
X2107183Y1934334D01*
X2106309Y1936376D01*
X2105873Y1938709D01*
X2106309Y1941043D01*
X2107183Y1943084D01*
X2108493Y1944251D01*
X2109803Y1944542D01*
X2111113Y1944251D01*
X2112423Y1943084D01*
X2113296Y1941043D01*
X2113515Y1938709D01*
X2113296Y1936376D01*
X2112423Y1934334D01*
X2111113Y1933168D01*
X2109803Y1932876D01*
G01X2127303Y1950376D02*
Y1932876D01*
G01X2124246Y1944542D02*
X2130360D01*
G01X2141528Y1940751D02*
X2148515D01*
X2147860Y1942793D01*
X2146768Y1943959D01*
X2145240Y1944542D01*
X2143711Y1944251D01*
X2142401Y1943376D01*
X2141528Y1941334D01*
X2141091Y1939584D01*
Y1937834D01*
X2141528Y1936084D01*
X2142620Y1934334D01*
X2143930Y1933168D01*
X2145458Y1932876D01*
X2146986Y1933459D01*
X2148515Y1935209D01*
G01X2159028Y1934917D02*
X2160120Y1933751D01*
X2161648Y1932876D01*
X2162958D01*
X2164268Y1933459D01*
X2165141Y1934334D01*
X2165578Y1935500D01*
X2165360Y1937251D01*
X2164486Y1938126D01*
X2160556Y1939876D01*
X2159683Y1941918D01*
X2160120Y1943376D01*
X2160993Y1944251D01*
X2162303Y1944542D01*
X2163613Y1944251D01*
X2164923Y1943376D01*
G01X2197303Y1950376D02*
Y1932876D01*
G01X2194246Y1944542D02*
X2200360D01*
G01X2211091Y1932876D02*
Y1950376D01*
G01Y1941918D02*
X2212183Y1943376D01*
X2213275Y1944251D01*
X2215021Y1944542D01*
X2216331Y1944251D01*
X2217860Y1943084D01*
X2218515Y1941334D01*
Y1932876D01*
G01X2236233D02*
Y1944542D01*
G01Y1942501D02*
X2235360Y1943667D01*
X2234049Y1944251D01*
X2232521Y1944542D01*
X2230993Y1943959D01*
X2229683Y1942793D01*
X2228809Y1941043D01*
X2228373Y1938709D01*
X2228809Y1936376D01*
X2229683Y1934626D01*
X2230993Y1933459D01*
X2232521Y1932876D01*
X2234049Y1933168D01*
X2235360Y1934042D01*
X2236233Y1935209D01*
G01X2249803Y1950376D02*
Y1932876D01*
G01X2246746Y1944542D02*
X2252860D01*
G01X2284803Y1950376D02*
Y1932876D01*
G01X2281746Y1944542D02*
X2287860D01*
G01X2298591Y1932876D02*
Y1950376D01*
G01Y1941918D02*
X2299683Y1943376D01*
X2300775Y1944251D01*
X2302521Y1944542D01*
X2303831Y1944251D01*
X2305360Y1943084D01*
X2306015Y1941334D01*
Y1932876D01*
G01X2319803Y1944542D02*
Y1932876D01*
G01Y1949209D02*
X2319366Y1949501D01*
Y1950084D01*
X2319803Y1950376D01*
X2320240Y1950084D01*
Y1949501D01*
X2319803Y1949209D01*
G01X2334028Y1934917D02*
X2335120Y1933751D01*
X2336648Y1932876D01*
X2337958D01*
X2339268Y1933459D01*
X2340141Y1934334D01*
X2340578Y1935500D01*
X2340360Y1937251D01*
X2339486Y1938126D01*
X2335556Y1939876D01*
X2334683Y1941918D01*
X2335120Y1943376D01*
X2335993Y1944251D01*
X2337303Y1944542D01*
X2338613Y1944251D01*
X2339923Y1943376D01*
G01X2369683Y1950376D02*
X2374923D01*
G01X2372303D02*
Y1932876D01*
G01X2369683D02*
X2374923D01*
G01X2383253D02*
Y1944542D01*
G01Y1941334D02*
X2383908Y1942793D01*
X2385000Y1943959D01*
X2386528Y1944542D01*
X2388056Y1943959D01*
X2389148Y1942793D01*
X2389803Y1941334D01*
Y1932876D01*
G01Y1941334D02*
X2390458Y1942793D01*
X2391549Y1943959D01*
X2393078Y1944542D01*
X2394606Y1943959D01*
X2395698Y1942793D01*
X2396353Y1941043D01*
Y1932876D01*
G01X2403373Y1927043D02*
Y1944542D01*
G01Y1941918D02*
X2404465Y1943376D01*
X2405556Y1944251D01*
X2407303Y1944542D01*
X2408831Y1944251D01*
X2410360Y1942793D01*
X2411015Y1940751D01*
X2411233Y1938709D01*
X2411015Y1936667D01*
X2410360Y1934626D01*
X2409049Y1933459D01*
X2407303Y1932876D01*
X2405775Y1933168D01*
X2404246Y1934042D01*
X2403373Y1935209D01*
G01X2421528Y1940751D02*
X2428515D01*
X2427860Y1942793D01*
X2426768Y1943959D01*
X2425240Y1944542D01*
X2423711Y1944251D01*
X2422401Y1943376D01*
X2421528Y1941334D01*
X2421091Y1939584D01*
Y1937834D01*
X2421528Y1936084D01*
X2422620Y1934334D01*
X2423930Y1933168D01*
X2425458Y1932876D01*
X2426986Y1933459D01*
X2428515Y1935209D01*
G01X2446233Y1950376D02*
Y1932876D01*
G01Y1935500D02*
X2445360Y1934042D01*
X2444049Y1933168D01*
X2442521Y1932876D01*
X2440775Y1933459D01*
X2439465Y1934917D01*
X2438591Y1936667D01*
X2438373Y1938709D01*
X2438591Y1940751D01*
X2439465Y1942501D01*
X2440775Y1943959D01*
X2442521Y1944542D01*
X2444049Y1944251D01*
X2445141Y1943667D01*
X2446233Y1942501D01*
G01X2463733Y1932876D02*
Y1944542D01*
G01Y1942501D02*
X2462860Y1943667D01*
X2461549Y1944251D01*
X2460021Y1944542D01*
X2458493Y1943959D01*
X2457183Y1942793D01*
X2456309Y1941043D01*
X2455873Y1938709D01*
X2456309Y1936376D01*
X2457183Y1934626D01*
X2458493Y1933459D01*
X2460021Y1932876D01*
X2461549Y1933168D01*
X2462860Y1934042D01*
X2463733Y1935209D01*
G01X2473591Y1932876D02*
Y1944542D01*
G01Y1941626D02*
X2474465Y1943084D01*
X2475775Y1944251D01*
X2477521Y1944542D01*
X2479049Y1944251D01*
X2480360Y1943084D01*
X2481015Y1941043D01*
Y1932876D01*
G01X2498296Y1943084D02*
X2496768Y1944251D01*
X2495458Y1944542D01*
X2493711Y1943959D01*
X2492401Y1942793D01*
X2491528Y1940751D01*
X2491309Y1938709D01*
X2491528Y1936667D01*
X2492401Y1934917D01*
X2493711Y1933459D01*
X2495458Y1932876D01*
X2496986Y1933459D01*
X2498296Y1934626D01*
G01X2509028Y1940751D02*
X2516015D01*
X2515360Y1942793D01*
X2514268Y1943959D01*
X2512740Y1944542D01*
X2511211Y1944251D01*
X2509901Y1943376D01*
X2509028Y1941334D01*
X2508591Y1939584D01*
Y1937834D01*
X2509028Y1936084D01*
X2510120Y1934334D01*
X2511430Y1933168D01*
X2512958Y1932876D01*
X2514486Y1933459D01*
X2516015Y1935209D01*
G01X2057303Y1909892D02*
Y1898226D01*
G01Y1914559D02*
X2056866Y1914851D01*
Y1915434D01*
X2057303Y1915726D01*
X2057740Y1915434D01*
Y1914851D01*
X2057303Y1914559D01*
G01X2071528Y1900267D02*
X2072620Y1899101D01*
X2074148Y1898226D01*
X2075458D01*
X2076768Y1898809D01*
X2077641Y1899684D01*
X2078078Y1900850D01*
X2077860Y1902601D01*
X2076986Y1903476D01*
X2073056Y1905226D01*
X2072183Y1907268D01*
X2072620Y1908726D01*
X2073493Y1909601D01*
X2074803Y1909892D01*
X2076113Y1909601D01*
X2077423Y1908726D01*
G01X2104781Y1898226D02*
Y1915726D01*
X2114825Y1898226D01*
Y1915726D01*
G01X2127303Y1898226D02*
X2125556Y1898518D01*
X2124028Y1899684D01*
X2122718Y1901434D01*
X2121844Y1903476D01*
X2121408Y1905809D01*
Y1908143D01*
X2121844Y1910476D01*
X2122718Y1912518D01*
X2124028Y1914267D01*
X2125556Y1915434D01*
X2127303Y1915726D01*
X2129049Y1915434D01*
X2130578Y1914267D01*
X2131888Y1912518D01*
X2132762Y1910476D01*
X2133198Y1908143D01*
Y1905809D01*
X2132762Y1903476D01*
X2131888Y1901434D01*
X2130578Y1899684D01*
X2129049Y1898518D01*
X2127303Y1898226D01*
G01X2144803Y1915726D02*
Y1898226D01*
G01X2139781Y1915726D02*
X2149825D01*
G01X2176091Y1909892D02*
Y1901726D01*
X2176965Y1899684D01*
X2178275Y1898518D01*
X2179803Y1898226D01*
X2181331Y1898518D01*
X2182641Y1899684D01*
X2183515Y1901726D01*
G01Y1898226D02*
Y1909892D01*
G01X2194028Y1900267D02*
X2195120Y1899101D01*
X2196648Y1898226D01*
X2197958D01*
X2199268Y1898809D01*
X2200141Y1899684D01*
X2200578Y1900850D01*
X2200360Y1902601D01*
X2199486Y1903476D01*
X2195556Y1905226D01*
X2194683Y1907268D01*
X2195120Y1908726D01*
X2195993Y1909601D01*
X2197303Y1909892D01*
X2198613Y1909601D01*
X2199923Y1908726D01*
G01X2211528Y1906101D02*
X2218515D01*
X2217860Y1908143D01*
X2216768Y1909309D01*
X2215240Y1909892D01*
X2213711Y1909601D01*
X2212401Y1908726D01*
X2211528Y1906684D01*
X2211091Y1904934D01*
Y1903184D01*
X2211528Y1901434D01*
X2212620Y1899684D01*
X2213930Y1898518D01*
X2215458Y1898226D01*
X2216986Y1898809D01*
X2218515Y1900559D01*
G01X2236233Y1915726D02*
Y1898226D01*
G01Y1900850D02*
X2235360Y1899392D01*
X2234049Y1898518D01*
X2232521Y1898226D01*
X2230775Y1898809D01*
X2229465Y1900267D01*
X2228591Y1902017D01*
X2228373Y1904059D01*
X2228591Y1906101D01*
X2229465Y1907851D01*
X2230775Y1909309D01*
X2232521Y1909892D01*
X2234049Y1909601D01*
X2235141Y1909017D01*
X2236233Y1907851D01*
G01X-7874Y0D02*
X-75552D01*
G02X-90552Y15000I0J15000D01*
G01Y519024D01*
G02X-75552Y534024I15000J0D01*
G01X-7874D01*
G01Y1030087D02*
X-75552D01*
G03X-90552Y1015087I0J-15000D01*
G01Y1001780D01*
G03X-75552Y986780I15000J0D01*
G01X-7874D01*
G01Y1992126D02*
X-75552D01*
G03X-90552Y1977126I0J-15000D01*
G01Y1915165D01*
G03X-75552Y1900165I15000J0D01*
G01X-7874D01*
G01X1023228Y1618051D02*
Y1675945D01*
G02X1028701Y1681417I5472J0D01*
G01X1033465D01*
X1037402Y1685354D01*
Y1988189D01*
G03X1033465Y1992126I-3937J0D01*
G01X3937D01*
G03X0Y1988189I0J-3937D01*
G01Y1661189D01*
X1969Y1659220D01*
X17323D01*
G02Y1650559I0J-4331D01*
G01X1969D01*
X0Y1648591D01*
Y1243866D01*
X1969Y1241898D01*
X17323D01*
G02Y1233236I0J-4331D01*
G01X1969D01*
X0Y1231268D01*
Y747803D01*
X1969Y745835D01*
X17323D01*
G02Y737173I0J-4331D01*
G01X1969D01*
X0Y735205D01*
Y3937D01*
G03X3937Y0I3937J0D01*
G01X121260D01*
X127310Y11888D01*
G03X127953Y14567I-5263J2680D01*
G01Y17717D01*
G02X139764I5906J0D01*
G01Y14567D01*
G03X140406Y11888I5906J-1D01*
G01X146457Y0D01*
X1033465D01*
G03X1037402Y3937I0J3937D01*
G01Y1424882D01*
X1033465Y1428819D01*
X1028701D01*
G02X1023228Y1434291I0J5473D01*
G01Y1609902D01*
X1021260Y1611870D01*
X993681D01*
G02Y1616083I0J2107D01*
G01X1021260D01*
X1023228Y1618051D01*
G01X-7874Y39059D02*
G03X0I3937J0D01*
G01Y8350D02*
G03X-7874I-3937J0D01*
G01D02*
Y0D01*
G01Y251657D02*
Y39059D01*
G01X0Y251657D02*
G03X-7874I-3937J0D01*
G01Y282366D02*
G03X0I3937J0D01*
G01X-7874Y494965D02*
Y282366D01*
G01Y525673D02*
G03X0I3937J0D01*
G01Y494965D02*
G03X-7874I-3937J0D01*
G01Y534024D02*
Y525673D01*
G01X0Y993079D02*
G03X-7874I-3937J0D01*
G01Y986780D02*
Y993079D01*
G01Y1023787D02*
G03X0I3937J0D01*
G01X-7874D02*
Y1030087D01*
G01Y1930791D02*
Y1900165D01*
G01X0Y1930791D02*
G03X-7874I-3937J0D01*
G01Y1961500D02*
G03X0I3937J0D01*
G01X-7874Y1992126D02*
Y1961500D01*
G01X1045276Y0D02*
X1112953D01*
G03X1127953Y15000I0J15000D01*
G01Y493259D01*
G01X1045276Y25827D02*
G03X1037402I-3937J0D01*
G01X1045276Y0D02*
Y25827D01*
G01X1037402Y56535D02*
G03X1045276I3937J0D01*
G01D02*
Y284882D01*
G01X1037402Y315591D02*
G03X1045276I3937J0D01*
G01Y284882D02*
G03X1037402I-3937J0D01*
G01X1045276Y315591D02*
Y543937D01*
G01D02*
G03X1037402I-3937J0D01*
G01Y574646D02*
G03X1045276I3937J0D01*
G01D02*
Y802992D01*
G01X1037402Y833701D02*
G03X1045276I3937J0D01*
G01Y802992D02*
G03X1037402I-3937J0D01*
G01X1045276Y833701D02*
Y1062047D01*
G01D02*
G03X1037402I-3937J0D01*
G01Y1092756D02*
G03X1045276I3937J0D01*
G01D02*
Y1321102D01*
G01D02*
G03X1037402I-3937J0D01*
G01Y1351811D02*
G03X1045276I3937J0D01*
G01D02*
Y1377638D01*
G01D02*
X1112953D01*
G02X1127953Y1362638I0J-15000D01*
G01Y501133D01*
G01X1045276Y1732598D02*
X1112953D01*
G03X1127953Y1747598I0J15000D01*
G01Y1977126D01*
G03X1112953Y1992126I-15000J0D01*
G01X1045276D01*
G01X1037402Y1767835D02*
G03X1045276I3937J0D01*
G01Y1737126D02*
G03X1037402I-3937J0D01*
G01X1045276Y1767835D02*
Y1956890D01*
G01Y1732598D02*
Y1737126D01*
G01X1037402Y1987598D02*
G03X1045276I3937J0D01*
G01Y1956890D02*
G03X1037402I-3937J0D01*
G01X1045276Y1987598D02*
Y1992126D01*
G01X1127953Y501133D02*
G03Y493259I0J-3937D01*
G54D12*
G01X37316Y352541D02*
X104184Y257044D01*
G01X35991Y351992D02*
X102859Y256495D01*
G01X26903Y411644D02*
X37316Y352541D01*
G01X25481Y411644D02*
X35991Y351992D01*
G01D02*
X102859Y256495D01*
G01X37316Y352541D02*
X104184Y257044D01*
G01X25481Y411644D02*
X35991Y351992D01*
G01X26903Y411644D02*
X37316Y352541D01*
G01X51855Y553163D02*
X26903Y411644D01*
G01X50433Y553162D02*
X25481Y411644D01*
G01X50433Y553162D02*
X25481Y411644D01*
G01X51855Y553163D02*
X26903Y411644D01*
G01X36864Y629846D02*
X35833Y629664D01*
G01X38461Y628727D02*
X36864Y629846D01*
G01D02*
X35833Y629664D01*
G01X38461Y628727D02*
X36864Y629846D01*
G01X38601Y615326D02*
X46852Y603543D01*
G01X37595Y614320D02*
X38714Y612723D01*
G01X29248Y621874D02*
X38601Y615326D01*
G01X28699Y620549D02*
X37595Y614320D01*
G01X25584Y622520D02*
X29248Y621874D01*
G01X25461Y621120D02*
X28699Y620549D01*
G01X20898Y622520D02*
X25584D01*
G01X20902Y621120D02*
X25461D01*
G01X38601Y615326D02*
X46852Y603543D01*
G01X37595Y614320D02*
X38714Y612723D01*
G01X38601Y615326D02*
X46852Y603543D01*
G01X28699Y620549D02*
X37595Y614320D01*
G01X29248Y621874D02*
X38601Y615326D01*
G01X25461Y621120D02*
X28699Y620549D01*
G01X25584Y622520D02*
X29248Y621874D01*
G01X20902Y621120D02*
X25461D01*
G01X20898Y622520D02*
X25584D01*
G01X38423Y605452D02*
X42153Y600120D01*
G01X35452Y609241D02*
X39429Y606458D01*
G01X34903Y607916D02*
X38423Y605452D01*
G01X31595Y609921D02*
X35452Y609241D01*
G01X31472Y608521D02*
X34903Y607916D01*
G01X20899Y609921D02*
X31595D01*
G01X20901Y608521D02*
X31472D01*
G01X38423Y605452D02*
X42153Y600120D01*
G01X34903Y607916D02*
X38423Y605452D01*
G01X35452Y609241D02*
X39429Y606458D01*
G01X31472Y608521D02*
X34903Y607916D01*
G01X31595Y609921D02*
X35452Y609241D01*
G01X20901Y608521D02*
X31472D01*
G01X20899Y609921D02*
X31595D01*
G01X28123Y647716D02*
X20899D01*
G01X28000Y646316D02*
X20901D01*
G01X35107Y646485D02*
X28123Y647716D01*
G01X34558Y645160D02*
X28000Y646316D01*
G01X42978Y640974D02*
X35107Y646485D01*
G01X41972Y639968D02*
X34558Y645160D01*
G01X28000Y646316D02*
X20901D01*
G01X28123Y647716D02*
X20899D01*
G01X34558Y645160D02*
X28000Y646316D01*
G01X35107Y646485D02*
X28123Y647716D01*
G01X41972Y639968D02*
X34558Y645160D01*
G01X42978Y640974D02*
X35107Y646485D01*
G01X28123Y698110D02*
X20899D01*
G01X27999Y696710D02*
X20901D01*
G01X77309Y689438D02*
X28123Y698110D01*
G01X29919Y696371D02*
X27999Y696710D01*
G01X35218Y695437D02*
X33297Y695776D01*
G01X40516Y694503D02*
X38595Y694841D01*
G01X27999Y696710D02*
X20901D01*
G01X28123Y698110D02*
X20899D01*
G01X29919Y696371D02*
X27999Y696710D01*
G01X77309Y689438D02*
X28123Y698110D01*
G01X35218Y695437D02*
X33297Y695776D01*
G01X77309Y689438D02*
X28123Y698110D01*
G01X40516Y694503D02*
X38595Y694841D01*
G01X77309Y689438D02*
X28123Y698110D01*
G01X77309Y689438D02*
X28123Y698110D01*
G01X27879Y635161D02*
X20856D01*
G01X27756Y633761D02*
X20944D01*
G01X33007Y634257D02*
X27879Y635161D01*
G01X32458Y632932D02*
X27756Y633761D01*
G01X32457Y632932D02*
X32458D01*
G01X45196Y625721D02*
X33007Y634257D01*
G01X32457Y632932D02*
X32458D01*
G01X34054Y631813D02*
X32457Y632932D01*
G01X30319Y685512D02*
X90711Y674864D01*
G01X37286Y682862D02*
X30196Y684112D01*
G01X20898Y685512D02*
X30319D01*
G01X30196Y684112D02*
X20902D01*
G01X30196D02*
X20902D01*
G01X20898Y685512D02*
X30319D01*
G01X37286Y682862D02*
X30196Y684112D01*
G01X30319Y685512D02*
X90711Y674864D01*
G01X30319Y685512D02*
X90711Y674864D01*
G01X30319Y685512D02*
X90711Y674864D01*
G01X30319Y685512D02*
X90711Y674864D01*
G01X28123Y672913D02*
X20899D01*
G01X20901Y671513D02*
X28246D01*
G01X53610Y677407D02*
X28123Y672913D01*
G01X28246Y671513D02*
X37741Y673187D01*
G01X53610Y677407D02*
X28123Y672913D01*
G01X53610Y677407D02*
X28123Y672913D01*
G01X53610Y677407D02*
X28123Y672913D01*
G01X53610Y677407D02*
X28123Y672913D01*
G01X28246Y671513D02*
X37741Y673187D01*
G01X53610Y677407D02*
X28123Y672913D01*
G01X20901Y671513D02*
X28246D01*
G01X28123Y672913D02*
X20899D01*
G01X28123Y660315D02*
X20898D01*
G01X28247Y658915D02*
X20902D01*
G01X38228Y662119D02*
X28123Y660315D01*
G01X38778Y660795D02*
X28247Y658915D01*
G01X42480Y665096D02*
X38228Y662119D01*
G01X43029Y663771D02*
X38778Y660795D01*
G01X28247Y658915D02*
X20902D01*
G01X28123Y660315D02*
X20898D01*
G01X38778Y660795D02*
X28247Y658915D01*
G01X38228Y662119D02*
X28123Y660315D01*
G01X43029Y663771D02*
X38778Y660795D01*
G01X42480Y665096D02*
X38228Y662119D01*
G01X27756Y633761D02*
X20944D01*
G01X27879Y635161D02*
X20856D01*
G01X32458Y632932D02*
X27756Y633761D01*
G01X33007Y634257D02*
X27879Y635161D01*
G01X32457Y632932D02*
X32458D01*
G01X33007Y634257D02*
X27879Y635161D01*
G01X45196Y625721D02*
X33007Y634257D01*
G01X34054Y631813D02*
X32457Y632932D01*
G01X45196Y625721D02*
X33007Y634257D01*
G01X45196Y625721D02*
X33007Y634257D01*
G01X45196Y625721D02*
X33007Y634257D01*
G01X45196Y625721D02*
X33007Y634257D01*
G01X45196Y625721D02*
X33007Y634257D01*
G01X28442Y767401D02*
X20899D01*
G01X28000Y766001D02*
X20901D01*
G01X78507Y732346D02*
X28442Y767401D01*
G01X77501Y731340D02*
X28000Y766001D01*
G01D02*
X20901D01*
G01X28442Y767401D02*
X20899D01*
G01X77501Y731340D02*
X28000Y766001D01*
G01X78507Y732346D02*
X28442Y767401D01*
G01Y754803D02*
X86181Y714376D01*
G01X28000Y753403D02*
X85175Y713370D01*
G01X20899Y754803D02*
X28442D01*
G01X20901Y753403D02*
X28000D01*
G01D02*
X85175Y713370D01*
G01X28442Y754803D02*
X86181Y714376D01*
G01X20901Y753403D02*
X28000D01*
G01X20899Y754803D02*
X28442D01*
G01X28123Y723307D02*
X73107Y715377D01*
G01X32459Y721121D02*
X28000Y721907D01*
G01X36027Y720492D02*
X32459Y721121D01*
G01X72558Y714052D02*
X36027Y720492D01*
G01X20899Y723307D02*
X28123D01*
G01X28000Y721907D02*
X20901D01*
G01X28000D02*
X20901D01*
G01X20899Y723307D02*
X28123D01*
G01X32459Y721121D02*
X28000Y721907D01*
G01X28123Y723307D02*
X73107Y715377D01*
G01X36027Y720492D02*
X32459Y721121D01*
G01X28123Y723307D02*
X73107Y715377D01*
G01X72558Y714052D02*
X36027Y720492D01*
G01X28123Y723307D02*
X73107Y715377D01*
G01X28123Y710708D02*
X20899D01*
G01X28000Y709308D02*
X20901D01*
G01X69861Y703350D02*
X28123Y710708D01*
G01X31818Y708635D02*
X28000Y709308D01*
G01X69312Y702025D02*
X31818Y708635D01*
G01X28000Y709308D02*
X20901D01*
G01X28123Y710708D02*
X20899D01*
G01X31818Y708635D02*
X28000Y709308D01*
G01X69861Y703350D02*
X28123Y710708D01*
G01X69312Y702025D02*
X31818Y708635D01*
G01X69861Y703350D02*
X28123Y710708D01*
G01X28000Y827244D02*
X20899D01*
G01X27877Y825844D02*
X20901D01*
G01X30637Y826779D02*
X28000Y827244D01*
G01X29536Y825551D02*
X27877Y825844D01*
G01X30088Y825454D02*
X29536Y825551D01*
G01X34719Y823921D02*
X30637Y826779D01*
G01X30088Y825454D02*
X29536Y825551D01*
G01X33713Y822915D02*
X30088Y825454D01*
G01X38408Y818653D02*
X34719Y823921D01*
G01X35487Y820383D02*
X33713Y822915D01*
G01X37261Y817850D02*
X35487Y820383D01*
G01X88788Y746703D02*
X38408Y818653D01*
G01X87711Y745800D02*
X37261Y817850D01*
G01X27877Y825844D02*
X20901D01*
G01X28000Y827244D02*
X20899D01*
G01X29536Y825551D02*
X27877Y825844D01*
G01X30637Y826779D02*
X28000Y827244D01*
G01X30088Y825454D02*
X29536Y825551D01*
G01X30637Y826779D02*
X28000Y827244D01*
G01X34719Y823921D02*
X30637Y826779D01*
G01X33713Y822915D02*
X30088Y825454D01*
G01X34719Y823921D02*
X30637Y826779D01*
G01X35487Y820383D02*
X33713Y822915D01*
G01X38408Y818653D02*
X34719Y823921D01*
G01X37261Y817850D02*
X35487Y820383D01*
G01X38408Y818653D02*
X34719Y823921D01*
G01X87711Y745800D02*
X37261Y817850D01*
G01X88788Y746703D02*
X38408Y818653D01*
G01X30136Y814269D02*
X42518Y805598D01*
G01X29587Y812944D02*
X41511Y804594D01*
G01X28000Y814646D02*
X30136Y814269D01*
G01X27877Y813246D02*
X29587Y812944D01*
G01X20898Y814646D02*
X28000D01*
G01X20902Y813246D02*
X27877D01*
G01X29587Y812944D02*
X41511Y804594D01*
G01X30136Y814269D02*
X42518Y805598D01*
G01X27877Y813246D02*
X29587Y812944D01*
G01X28000Y814646D02*
X30136Y814269D01*
G01X20902Y813246D02*
X27877D01*
G01X20898Y814646D02*
X28000D01*
G01Y802047D02*
X20899D01*
G01X27877Y800647D02*
X20901D01*
G01X31744Y801386D02*
X28000Y802047D01*
G01X31195Y800061D02*
X27877Y800647D01*
G01X48754Y789477D02*
X31744Y801386D01*
G01X47748Y788471D02*
X31195Y800061D01*
G01X27877Y800647D02*
X20901D01*
G01X28000Y802047D02*
X20899D01*
G01X31195Y800061D02*
X27877Y800647D01*
G01X31744Y801386D02*
X28000Y802047D01*
G01X47748Y788471D02*
X31195Y800061D01*
G01X48754Y789477D02*
X31744Y801386D01*
G01X28123Y789449D02*
X20898D01*
G01X28000Y788049D02*
X20902D01*
G01X33264Y788543D02*
X28123Y789449D01*
G01X32715Y787218D02*
X28000Y788049D01*
G01X55812Y772756D02*
X33264Y788543D01*
G01X54806Y771750D02*
X32715Y787218D01*
G01X28000Y788049D02*
X20902D01*
G01X28123Y789449D02*
X20898D01*
G01X32715Y787218D02*
X28000Y788049D01*
G01X33264Y788543D02*
X28123Y789449D01*
G01X54806Y771750D02*
X32715Y787218D01*
G01X55812Y772756D02*
X33264Y788543D01*
G01X46680Y826442D02*
X30105Y838049D01*
G01X46680Y826442D02*
X30105Y838049D01*
G01X46680Y826442D02*
X30105Y838049D01*
G01X36658Y835170D02*
X37689Y835351D01*
G01X46680Y826442D02*
X30105Y838049D01*
G01X35061Y836288D02*
X36658Y835170D01*
G01X46680Y826442D02*
X30105Y838049D01*
G01X32251Y838256D02*
X33282Y838437D01*
G01X46680Y826442D02*
X30105Y838049D01*
G01X30654Y839374D02*
X32251Y838256D01*
G01X46680Y826442D02*
X30105Y838049D01*
G01X28000Y839842D02*
X30654Y839374D01*
G01X30105Y838049D02*
X27877Y838442D01*
G01X20899Y839842D02*
X28000D01*
G01X27877Y838442D02*
X20901D01*
G01X27877D02*
X20901D01*
G01X20899Y839842D02*
X28000D01*
G01X30105Y838049D02*
X27877Y838442D01*
G01X28000Y839842D02*
X30654Y839374D01*
G01X46680Y826442D02*
X30105Y838049D01*
G01X36658Y835170D02*
X37689Y835351D01*
G01X35061Y836288D02*
X36658Y835170D01*
G01X32251Y838256D02*
X33282Y838437D01*
G01X30654Y839374D02*
X32251Y838256D01*
G01X28000Y877638D02*
X20898D01*
G01X27877Y876238D02*
X20902D01*
G01X41694Y875225D02*
X28000Y877638D01*
G01X41145Y873900D02*
X27877Y876238D01*
G01D02*
X20902D01*
G01X28000Y877638D02*
X20898D01*
G01X41145Y873900D02*
X27877Y876238D01*
G01X41694Y875225D02*
X28000Y877638D01*
G01Y865039D02*
X40839Y862775D01*
G01X27877Y863639D02*
X40290Y861450D01*
G01X20899Y865039D02*
X28000D01*
G01X20901Y863639D02*
X27877D01*
G01D02*
X40290Y861450D01*
G01X28000Y865039D02*
X40839Y862775D01*
G01X20901Y863639D02*
X27877D01*
G01X20899Y865039D02*
X28000D01*
G01X24168Y915433D02*
X20899D01*
G01X24291Y914033D02*
X20901D01*
G01X31387Y916705D02*
X24168Y915433D01*
G01X31936Y915380D02*
X24291Y914033D01*
G01X37999Y921334D02*
X31387Y916705D01*
G01X39005Y920328D02*
X31936Y915380D01*
G01X24291Y914033D02*
X20901D01*
G01X24168Y915433D02*
X20899D01*
G01X31936Y915380D02*
X24291Y914033D01*
G01X31387Y916705D02*
X24168Y915433D01*
G01X39005Y920328D02*
X31936Y915380D01*
G01X37999Y921334D02*
X31387Y916705D01*
G01X28000Y852441D02*
X20898D01*
G01X27877Y851041D02*
X20902D01*
G01X31123Y851890D02*
X28000Y852441D01*
G01X39408Y849006D02*
X27877Y851041D01*
G01X39957Y850331D02*
X34500Y851294D01*
G01X39408Y849006D02*
X27877Y851041D01*
G01D02*
X20902D01*
G01X28000Y852441D02*
X20898D01*
G01X39408Y849006D02*
X27877Y851041D01*
G01X31123Y851890D02*
X28000Y852441D01*
G01X39957Y850331D02*
X34500Y851294D01*
G01X31972Y902834D02*
X20899D01*
G01X32095Y901434D02*
X20901D01*
G01X35807Y903510D02*
X31972Y902834D01*
G01X36356Y902185D02*
X32095Y901434D01*
G01X39316Y905967D02*
X35807Y903510D01*
G01X40322Y904961D02*
X36356Y902185D01*
G01X32095Y901434D02*
X20901D01*
G01X31972Y902834D02*
X20899D01*
G01X36356Y902185D02*
X32095Y901434D01*
G01X35807Y903510D02*
X31972Y902834D01*
G01X40322Y904961D02*
X36356Y902185D01*
G01X39316Y905967D02*
X35807Y903510D01*
G01X48542Y936389D02*
X37999Y921334D01*
G01X48542Y936389D02*
X37999Y921334D01*
G01X27540Y1118583D02*
X42044Y1116025D01*
G01X27417Y1117183D02*
X41495Y1114699D01*
G01X20898Y1118583D02*
X27540D01*
G01X20902Y1117183D02*
X27417D01*
G01D02*
X41495Y1114699D01*
G01X27540Y1118583D02*
X42044Y1116025D01*
G01X20902Y1117183D02*
X27417D01*
G01X20898Y1118583D02*
X27540D01*
G01X28123Y1105984D02*
X20899D01*
G01X28000Y1104584D02*
X20901D01*
G01X42341Y1103477D02*
X28123Y1105984D01*
G01X41792Y1102151D02*
X28000Y1104584D01*
G01D02*
X20901D01*
G01X28123Y1105984D02*
X20899D01*
G01X41792Y1102151D02*
X28000Y1104584D01*
G01X42341Y1103477D02*
X28123Y1105984D01*
G01X70559Y1115690D02*
X32105Y1142608D01*
G01X69553Y1114684D02*
X31556Y1141283D01*
G01X69553Y1114684D02*
X31556Y1141283D01*
G01X70559Y1115690D02*
X32105Y1142608D01*
G01X30321Y1180666D02*
X59585Y1160198D01*
G01X29772Y1179340D02*
X58579Y1159192D01*
G01X25162Y1181575D02*
X30321Y1180666D01*
G01X25039Y1180175D02*
X29772Y1179340D01*
G01X20898Y1181575D02*
X25162D01*
G01X20902Y1180175D02*
X25039D01*
G01X29772Y1179340D02*
X58579Y1159192D01*
G01X30321Y1180666D02*
X59585Y1160198D01*
G01X25039Y1180175D02*
X29772Y1179340D01*
G01X25162Y1181575D02*
X30321Y1180666D01*
G01X20902Y1180175D02*
X25039D01*
G01X20898Y1181575D02*
X25162D01*
G01X29730Y1168976D02*
X20899D01*
G01X29607Y1167576D02*
X20901D01*
G01X33432Y1168322D02*
X29730Y1168976D01*
G01X32883Y1166997D02*
X29607Y1167576D01*
G01X41956Y1162353D02*
X33432Y1168322D01*
G01X41386Y1161042D02*
X32883Y1166997D01*
G01X29607Y1167576D02*
X20901D01*
G01X29730Y1168976D02*
X20899D01*
G01X32883Y1166997D02*
X29607Y1167576D01*
G01X33432Y1168322D02*
X29730Y1168976D01*
G01X41386Y1161042D02*
X32883Y1166997D01*
G01X41956Y1162353D02*
X33432Y1168322D01*
G01X28000Y1206771D02*
X20899D01*
G01X27877Y1205371D02*
X20901D01*
G01X36261Y1205314D02*
X28000Y1206771D01*
G01X35712Y1203989D02*
X27877Y1205371D01*
G01X44829Y1199315D02*
X36261Y1205314D01*
G01X43823Y1198309D02*
X35712Y1203989D01*
G01X27877Y1205371D02*
X20901D01*
G01X28000Y1206771D02*
X20899D01*
G01X35712Y1203989D02*
X27877Y1205371D01*
G01X36261Y1205314D02*
X28000Y1206771D01*
G01X43823Y1198309D02*
X35712Y1203989D01*
G01X44829Y1199315D02*
X36261Y1205314D01*
G01X33428Y1158187D02*
X40660Y1156909D01*
G01X33453Y1156760D02*
X40111Y1155584D01*
G01X24920Y1156378D02*
X33428Y1158187D01*
G01X25068Y1154978D02*
X33453Y1156760D01*
G01X20898Y1156378D02*
X24920D01*
G01X20902Y1154978D02*
X25068D01*
G01X33453Y1156760D02*
X40111Y1155584D01*
G01X33428Y1158187D02*
X40660Y1156909D01*
G01X25068Y1154978D02*
X33453Y1156760D01*
G01X24920Y1156378D02*
X33428Y1158187D01*
G01X20902Y1154978D02*
X25068D01*
G01X20898Y1156378D02*
X24920D01*
G01X28123Y1194173D02*
X20899D01*
G01X28000Y1192773D02*
X20901D01*
G01X30706Y1193718D02*
X28123Y1194173D01*
G01X30155Y1192393D02*
X28000Y1192773D01*
G01X54406Y1177129D02*
X30706Y1193718D01*
G01X53400Y1176123D02*
X30157Y1192392D01*
G01X28000Y1192773D02*
X20901D01*
G01X28123Y1194173D02*
X20899D01*
G01X30155Y1192393D02*
X28000Y1192773D01*
G01X30706Y1193718D02*
X28123Y1194173D01*
G01X53400Y1176123D02*
X30157Y1192392D01*
G01X54406Y1177129D02*
X30706Y1193718D01*
G01X25463Y1143779D02*
X20899D01*
G01X25340Y1142379D02*
X20901D01*
G01X32105Y1142608D02*
X25463Y1143779D01*
G01X31556Y1141283D02*
X25340Y1142379D01*
G01D02*
X20901D01*
G01X25463Y1143779D02*
X20899D01*
G01X31556Y1141283D02*
X25340Y1142379D01*
G01X32105Y1142608D02*
X25463Y1143779D01*
G01X44866Y1278890D02*
X34609Y1286074D01*
G01X28000Y1250866D02*
X20899D01*
G01X27877Y1249466D02*
X20901D01*
G01X32370Y1250095D02*
X28000Y1250866D01*
G01X31821Y1248770D02*
X27877Y1249466D01*
G01X37871Y1246244D02*
X32370Y1250095D01*
G01X36865Y1245238D02*
X31821Y1248770D01*
G01X43641Y1238002D02*
X37871Y1246244D01*
G01X42316Y1237453D02*
X36865Y1245238D01*
G01X27877Y1249466D02*
X20901D01*
G01X28000Y1250866D02*
X20899D01*
G01X31821Y1248770D02*
X27877Y1249466D01*
G01X32370Y1250095D02*
X28000Y1250866D01*
G01X36865Y1245238D02*
X31821Y1248770D01*
G01X37871Y1246244D02*
X32370Y1250095D01*
G01X42316Y1237453D02*
X36865Y1245238D01*
G01X43641Y1238002D02*
X37871Y1246244D01*
G01X28000Y1219370D02*
X20899D01*
G01X27877Y1217970D02*
X20901D01*
G01X33806Y1218346D02*
X28000Y1219370D01*
G01X33257Y1217021D02*
X27877Y1217970D01*
G01X41175Y1213187D02*
X33806Y1218346D01*
G01X40169Y1212181D02*
X33257Y1217021D01*
G01X27877Y1217970D02*
X20901D01*
G01X28000Y1219370D02*
X20899D01*
G01X33257Y1217021D02*
X27877Y1217970D01*
G01X33806Y1218346D02*
X28000Y1219370D01*
G01X40169Y1212181D02*
X33257Y1217021D01*
G01X41175Y1213187D02*
X33806Y1218346D01*
G01X44866Y1278890D02*
X34609Y1286074D01*
G01X28000Y1276063D02*
X20898D01*
G01X27877Y1274663D02*
X20902D01*
G01X34571Y1274904D02*
X28000Y1276063D01*
G01X34022Y1273579D02*
X27877Y1274663D01*
G01X41722Y1269897D02*
X34571Y1274904D01*
G01X40716Y1268891D02*
X34022Y1273579D01*
G01X27877Y1274663D02*
X20902D01*
G01X28000Y1276063D02*
X20898D01*
G01X34022Y1273579D02*
X27877Y1274663D01*
G01X34571Y1274904D02*
X28000Y1276063D01*
G01X40716Y1268891D02*
X34022Y1273579D01*
G01X41722Y1269897D02*
X34571Y1274904D01*
G01X35296Y1262178D02*
X41969Y1257505D01*
G01X34747Y1260853D02*
X40963Y1256499D01*
G01X28000Y1263464D02*
X35296Y1262178D01*
G01X27877Y1262064D02*
X34747Y1260853D01*
G01X20899Y1263464D02*
X28000D01*
G01X20901Y1262064D02*
X27877D01*
G01X34747Y1260853D02*
X40963Y1256499D01*
G01X35296Y1262178D02*
X41969Y1257505D01*
G01X27877Y1262064D02*
X34747Y1260853D01*
G01X28000Y1263464D02*
X35296Y1262178D01*
G01X20901Y1262064D02*
X27877D01*
G01X20899Y1263464D02*
X28000D01*
G01X26246Y1301260D02*
X20898D01*
G01X26123Y1299860D02*
X20902D01*
G01X29452Y1300695D02*
X26246Y1301260D01*
G01X28903Y1299370D02*
X26123Y1299860D01*
G01X47236Y1288243D02*
X29452Y1300695D01*
G01X46230Y1287237D02*
X28903Y1299370D01*
G01X26123Y1299860D02*
X20902D01*
G01X26246Y1301260D02*
X20898D01*
G01X28903Y1299370D02*
X26123Y1299860D01*
G01X29452Y1300695D02*
X26246Y1301260D01*
G01X46230Y1287237D02*
X28903Y1299370D01*
G01X47236Y1288243D02*
X29452Y1300695D01*
G01X28000Y1288661D02*
X20899D01*
G01X27877Y1287261D02*
X20901D01*
G01X35158Y1287399D02*
X28000Y1288661D01*
G01X34609Y1286074D02*
X27877Y1287261D01*
G01X45872Y1279896D02*
X35158Y1287399D01*
G01X27544Y1348467D02*
X20935D01*
G01X27667Y1347067D02*
X20865D01*
G01X34247Y1349649D02*
X27544Y1348467D01*
G01X34796Y1348324D02*
X27667Y1347067D01*
G01X42073Y1355131D02*
X34247Y1349649D01*
G01X43079Y1354125D02*
X34796Y1348324D01*
G01X27667Y1347067D02*
X20865D01*
G01X27544Y1348467D02*
X20935D01*
G01X34796Y1348324D02*
X27667Y1347067D01*
G01X34247Y1349649D02*
X27544Y1348467D01*
G01X43079Y1354125D02*
X34796Y1348324D01*
G01X42073Y1355131D02*
X34247Y1349649D01*
G01X27877Y1335905D02*
X20899D01*
G01X28000Y1334505D02*
X20901D01*
G01X33297Y1336861D02*
X27877Y1335905D01*
G01X33846Y1335536D02*
X28000Y1334505D01*
G01X41282Y1342452D02*
X33297Y1336861D01*
G01X35443Y1336654D02*
X33846Y1335536D01*
G01X36474Y1336473D02*
X35443Y1336654D01*
G01X39850Y1339740D02*
X38253Y1338622D01*
G01X28000Y1334505D02*
X20901D01*
G01X27877Y1335905D02*
X20899D01*
G01X33846Y1335536D02*
X28000Y1334505D01*
G01X33297Y1336861D02*
X27877Y1335905D01*
G01X35443Y1336654D02*
X33846Y1335536D01*
G01X41282Y1342452D02*
X33297Y1336861D01*
G01X36474Y1336473D02*
X35443Y1336654D01*
G01X41282Y1342452D02*
X33297Y1336861D01*
G01X39850Y1339740D02*
X38253Y1338622D01*
G01X41282Y1342452D02*
X33297Y1336861D01*
G01X41282Y1342452D02*
X33297Y1336861D01*
G01X27877Y1323307D02*
X20899D01*
G01X28000Y1321907D02*
X20901D01*
G01X31118Y1323879D02*
X27877Y1323307D01*
G01X31667Y1322554D02*
X28000Y1321907D01*
G01X32715Y1324997D02*
X31118Y1323879D01*
G01X49593Y1335103D02*
X31667Y1322554D01*
G01X35525Y1326965D02*
X34495Y1327146D01*
G01X49593Y1335103D02*
X31667Y1322554D01*
G01X37122Y1328083D02*
X35525Y1326965D01*
G01X49593Y1335103D02*
X31667Y1322554D01*
G01X49593Y1335103D02*
X31667Y1322554D01*
G01X49593Y1335103D02*
X31667Y1322554D01*
G01X49593Y1335103D02*
X31667Y1322554D01*
G01X49593Y1335103D02*
X31667Y1322554D01*
G01X28000Y1321907D02*
X20901D01*
G01X27877Y1323307D02*
X20899D01*
G01X31667Y1322554D02*
X28000Y1321907D01*
G01X31118Y1323879D02*
X27877Y1323307D01*
G01X49593Y1335103D02*
X31667Y1322554D01*
G01X32715Y1324997D02*
X31118Y1323879D01*
G01X35525Y1326965D02*
X34495Y1327146D01*
G01X37122Y1328083D02*
X35525Y1326965D01*
G01X27877Y1287261D02*
X20901D01*
G01X28000Y1288661D02*
X20899D01*
G01X34609Y1286074D02*
X27877Y1287261D01*
G01X35158Y1287399D02*
X28000Y1288661D01*
G01X45872Y1279896D02*
X35158Y1287399D01*
G01X27877Y1411496D02*
X20899D01*
G01X28000Y1410096D02*
X20901D01*
G01X30515Y1411961D02*
X27877Y1411496D01*
G01X31064Y1410636D02*
X28000Y1410096D01*
G01X34628Y1414842D02*
X30515Y1411961D01*
G01X35634Y1413836D02*
X31064Y1410636D01*
G01X49741Y1436417D02*
X34628Y1414842D01*
G01X51066Y1435868D02*
X35634Y1413836D01*
G01X28000Y1410096D02*
X20901D01*
G01X27877Y1411496D02*
X20899D01*
G01X31064Y1410636D02*
X28000Y1410096D01*
G01X30515Y1411961D02*
X27877Y1411496D01*
G01X35634Y1413836D02*
X31064Y1410636D01*
G01X34628Y1414842D02*
X30515Y1411961D01*
G01X51066Y1435868D02*
X35634Y1413836D01*
G01X49741Y1436417D02*
X34628Y1414842D01*
G01X27754Y1361102D02*
X20899D01*
G01X27877Y1359702D02*
X20901D01*
G01X30750Y1361630D02*
X27754Y1361102D01*
G01X31299Y1360305D02*
X27877Y1359702D01*
G01X47188Y1373143D02*
X30750Y1361630D01*
G01X37872Y1364908D02*
X31299Y1360305D01*
G01X38847Y1364736D02*
X37872Y1364908D01*
G01X27877Y1359702D02*
X20901D01*
G01X27754Y1361102D02*
X20899D01*
G01X31299Y1360305D02*
X27877Y1359702D01*
G01X30750Y1361630D02*
X27754Y1361102D01*
G01X37872Y1364908D02*
X31299Y1360305D01*
G01X47188Y1373143D02*
X30750Y1361630D01*
G01X38847Y1364736D02*
X37872Y1364908D01*
G01X47188Y1373143D02*
X30750Y1361630D01*
G01X47188Y1373143D02*
X30750Y1361630D01*
G01X47188Y1373143D02*
X30750Y1361630D01*
G01X47188Y1373143D02*
X30750Y1361630D01*
G01X27877Y1398897D02*
X20899D01*
G01X28000Y1397497D02*
X20901D01*
G01X37858Y1400658D02*
X27877Y1398897D01*
G01X38407Y1399333D02*
X28000Y1397497D01*
G01X45494Y1406006D02*
X37858Y1400658D01*
G01X46500Y1405000D02*
X38407Y1399333D01*
G01X28000Y1397497D02*
X20901D01*
G01X27877Y1398897D02*
X20899D01*
G01X38407Y1399333D02*
X28000Y1397497D01*
G01X37858Y1400658D02*
X27877Y1398897D01*
G01X46500Y1405000D02*
X38407Y1399333D01*
G01X45494Y1406006D02*
X37858Y1400658D01*
G01X27877Y1386299D02*
X20899D01*
G01X28000Y1384899D02*
X20901D01*
G01X31690Y1386971D02*
X27877Y1386299D01*
G01X32239Y1385646D02*
X28000Y1384899D01*
G01X41161Y1393604D02*
X31690Y1386971D01*
G01X42167Y1392598D02*
X32239Y1385646D01*
G01X28000Y1384899D02*
X20901D01*
G01X27877Y1386299D02*
X20899D01*
G01X32239Y1385646D02*
X28000Y1384899D01*
G01X31690Y1386971D02*
X27877Y1386299D01*
G01X42167Y1392598D02*
X32239Y1385646D01*
G01X41161Y1393604D02*
X31690Y1386971D01*
G01X27877Y1373701D02*
X20898D01*
G01X28000Y1372301D02*
X20902D01*
G01X30594Y1374180D02*
X27877Y1373701D01*
G01X31143Y1372855D02*
X28000Y1372301D01*
G01X33857Y1376465D02*
X30594Y1374180D01*
G01X34863Y1375459D02*
X31143Y1372855D01*
G01X62415Y1417250D02*
X33857Y1376465D01*
G01X63421Y1416244D02*
X34863Y1375459D01*
G01X28000Y1372301D02*
X20902D01*
G01X27877Y1373701D02*
X20898D01*
G01X31143Y1372855D02*
X28000Y1372301D01*
G01X30594Y1374180D02*
X27877Y1373701D01*
G01X34863Y1375459D02*
X31143Y1372855D01*
G01X33857Y1376465D02*
X30594Y1374180D01*
G01X63421Y1416244D02*
X34863Y1375459D01*
G01X62415Y1417250D02*
X33857Y1376465D01*
G01X27877Y1570550D02*
X47127Y1573944D01*
G01X28000Y1569150D02*
X47676Y1572619D01*
G01X20899Y1570550D02*
X27877D01*
G01X20901Y1569150D02*
X28000D01*
G01D02*
X47676Y1572619D01*
G01X27877Y1570550D02*
X47127Y1573944D01*
G01X20901Y1569150D02*
X28000D01*
G01X20899Y1570550D02*
X27877D01*
G01Y1557952D02*
X20898D01*
G01X28000Y1556552D02*
X20902D01*
G01X36817Y1559528D02*
X27877Y1557952D01*
G01X37366Y1558203D02*
X28000Y1556552D01*
G01X58385Y1574629D02*
X36817Y1559528D01*
G01X81011Y1588762D02*
X37366Y1558203D01*
G01X81011Y1588762D02*
X37366Y1558203D01*
G01X28000Y1556552D02*
X20902D01*
G01X27877Y1557952D02*
X20898D01*
G01X37366Y1558203D02*
X28000Y1556552D01*
G01X36817Y1559528D02*
X27877Y1557952D01*
G01X81011Y1588762D02*
X37366Y1558203D01*
G01X58385Y1574629D02*
X36817Y1559528D01*
G01X27877Y1545353D02*
X20899D01*
G01X28000Y1543953D02*
X20901D01*
G01X30617Y1545836D02*
X27877Y1545353D01*
G01X31166Y1544511D02*
X28000Y1543953D01*
G01X90773Y1587958D02*
X30617Y1545836D01*
G01X91322Y1586633D02*
X31166Y1544511D01*
G01X28000Y1543953D02*
X20901D01*
G01X27877Y1545353D02*
X20899D01*
G01X31166Y1544511D02*
X28000Y1543953D01*
G01X30617Y1545836D02*
X27877Y1545353D01*
G01X91322Y1586633D02*
X31166Y1544511D01*
G01X90773Y1587958D02*
X30617Y1545836D01*
G01X24373Y1532755D02*
X20899D01*
G01X24496Y1531355D02*
X20901D01*
G01X29271Y1533618D02*
X24373Y1532755D01*
G01X29820Y1532293D02*
X24496Y1531355D01*
G01X38086Y1539792D02*
X29271Y1533618D01*
G01X39092Y1538786D02*
X29820Y1532293D01*
G01X47036Y1552575D02*
X38086Y1539792D01*
G01X24496Y1531355D02*
X20901D01*
G01X24373Y1532755D02*
X20899D01*
G01X29820Y1532293D02*
X24496Y1531355D01*
G01X29271Y1533618D02*
X24373Y1532755D01*
G01X39092Y1538786D02*
X29820Y1532293D01*
G01X38086Y1539792D02*
X29271Y1533618D01*
G01X47036Y1552575D02*
X38086Y1539792D01*
G01X27877Y1628993D02*
X20902D01*
G01X28000Y1630393D02*
X20898D01*
G01X55810Y1624069D02*
X27877Y1628993D01*
G01X56053Y1625448D02*
X28000Y1630393D01*
G01D02*
X20898D01*
G01X27877Y1628993D02*
X20902D01*
G01X56053Y1625448D02*
X28000Y1630393D01*
G01X55810Y1624069D02*
X27877Y1628993D01*
G01X41011Y1616394D02*
X20901D01*
G01X20899Y1617794D02*
X41012D01*
G01X20899D02*
X41012D01*
G01X41011Y1616394D02*
X20901D01*
G01X28123Y1603796D02*
X60222Y1598132D01*
G01X28246Y1605196D02*
X60222Y1599554D01*
G01X20902Y1603796D02*
X28123D01*
G01X20898Y1605196D02*
X28246D01*
G01D02*
X60222Y1599554D01*
G01X28123Y1603796D02*
X60222Y1598132D01*
G01X20898Y1605196D02*
X28246D01*
G01X20902Y1603796D02*
X28123D01*
G01Y1591197D02*
X20901D01*
G01X20899Y1592597D02*
X28000D01*
G01X51897Y1595390D02*
X28123Y1591197D01*
G01X28000Y1592597D02*
X51897Y1596812D01*
G01X28000Y1592597D02*
X51897Y1596812D01*
G01Y1595390D02*
X28123Y1591197D01*
G01X20899Y1592597D02*
X28000D01*
G01X28123Y1591197D02*
X20901D01*
G01X24224Y1642991D02*
X20899D01*
G01X24347Y1641591D02*
X20901D01*
G01X27154Y1643508D02*
X24224Y1642991D01*
G01X27703Y1642183D02*
X24347Y1641591D01*
G01X31154Y1646308D02*
X27154Y1643508D01*
G01X32160Y1645302D02*
X27703Y1642183D01*
G01X46087Y1667637D02*
X31154Y1646308D01*
G01X47412Y1667088D02*
X32160Y1645302D01*
G01X24347Y1641591D02*
X20901D01*
G01X24224Y1642991D02*
X20899D01*
G01X27703Y1642183D02*
X24347Y1641591D01*
G01X27154Y1643508D02*
X24224Y1642991D01*
G01X32160Y1645302D02*
X27703Y1642183D01*
G01X31154Y1646308D02*
X27154Y1643508D01*
G01X47412Y1667088D02*
X32160Y1645302D01*
G01X46087Y1667637D02*
X31154Y1646308D01*
G01X27877Y1693384D02*
X20899D01*
G01X28000Y1691984D02*
X20901D01*
G01X33643Y1694401D02*
X27877Y1693384D01*
G01X34192Y1693076D02*
X28000Y1691984D01*
G01X39095Y1698220D02*
X33643Y1694401D01*
G01X40101Y1697214D02*
X34192Y1693076D01*
G01X28000Y1691984D02*
X20901D01*
G01X27877Y1693384D02*
X20899D01*
G01X34192Y1693076D02*
X28000Y1691984D01*
G01X33643Y1694401D02*
X27877Y1693384D01*
G01X40101Y1697214D02*
X34192Y1693076D01*
G01X39095Y1698220D02*
X33643Y1694401D01*
G01X32004Y1681524D02*
X39035Y1686448D01*
G01X32553Y1680199D02*
X40041Y1685442D01*
G01X27818Y1680786D02*
X32004Y1681524D01*
G01X27941Y1679386D02*
X32553Y1680199D01*
G01X20899Y1680786D02*
X27818D01*
G01X20901Y1679386D02*
X27941D01*
G01X32553Y1680199D02*
X40041Y1685442D01*
G01X32004Y1681524D02*
X39035Y1686448D01*
G01X27941Y1679386D02*
X32553Y1680199D01*
G01X27818Y1680786D02*
X32004Y1681524D01*
G01X20901Y1679386D02*
X27941D01*
G01X20899Y1680786D02*
X27818D01*
G01X27877Y1668189D02*
X20898D01*
G01X28000Y1666789D02*
X20902D01*
G01X34618Y1669378D02*
X27877Y1668189D01*
G01X35167Y1668053D02*
X28000Y1666789D01*
G01X36166Y1670462D02*
X34618Y1669378D01*
G01X38721Y1670542D02*
X35167Y1668053D01*
G01X37621Y1671482D02*
X36166Y1670462D01*
G01X38721Y1670542D02*
X35167Y1668053D01*
G01X44330Y1680994D02*
X37781Y1671642D01*
G01X45738Y1680563D02*
X38721Y1670542D01*
G01X28000Y1666789D02*
X20902D01*
G01X27877Y1668189D02*
X20898D01*
G01X35167Y1668053D02*
X28000Y1666789D01*
G01X34618Y1669378D02*
X27877Y1668189D01*
G01X38721Y1670542D02*
X35167Y1668053D01*
G01X36166Y1670462D02*
X34618Y1669378D01*
G01X37621Y1671482D02*
X36166Y1670462D01*
G01X45738Y1680563D02*
X38721Y1670542D01*
G01X44330Y1680994D02*
X37781Y1671642D01*
G01X28000Y1714032D02*
X20901D01*
G01X27877Y1715432D02*
X20899D01*
G01X31246Y1714604D02*
X28000Y1714032D01*
G01X30697Y1715929D02*
X27877Y1715432D01*
G01X34924Y1717180D02*
X31246Y1714604D01*
G01X33918Y1718186D02*
X30697Y1715929D01*
G01X40872Y1725674D02*
X34924Y1717180D01*
G01X39547Y1726223D02*
X33918Y1718186D01*
G01X27877Y1715432D02*
X20899D01*
G01X28000Y1714032D02*
X20901D01*
G01X30697Y1715929D02*
X27877Y1715432D01*
G01X31246Y1714604D02*
X28000Y1714032D01*
G01X33918Y1718186D02*
X30697Y1715929D01*
G01X34924Y1717180D02*
X31246Y1714604D01*
G01X39547Y1726223D02*
X33918Y1718186D01*
G01X40872Y1725674D02*
X34924Y1717180D01*
G01X28000Y1751827D02*
X20901D01*
G01X27877Y1753227D02*
X20899D01*
G01X30711Y1752305D02*
X28000Y1751827D01*
G01X30162Y1753630D02*
X27877Y1753227D01*
G01X33178Y1754032D02*
X30711Y1752305D01*
G01X32172Y1755038D02*
X30162Y1753630D01*
G01X35321Y1757094D02*
X33178Y1754032D01*
G01X33996Y1757643D02*
X32173Y1755039D01*
G01X53205Y1858439D02*
X35321Y1757094D01*
G01X51880Y1858988D02*
X33996Y1757643D01*
G01X27877Y1753227D02*
X20899D01*
G01X28000Y1751827D02*
X20901D01*
G01X30162Y1753630D02*
X27877Y1753227D01*
G01X30711Y1752305D02*
X28000Y1751827D01*
G01X32172Y1755038D02*
X30162Y1753630D01*
G01X33178Y1754032D02*
X30711Y1752305D01*
G01X33996Y1757643D02*
X32173Y1755039D01*
G01X35321Y1757094D02*
X33178Y1754032D01*
G01X51880Y1858988D02*
X33996Y1757643D01*
G01X53205Y1858439D02*
X35321Y1757094D01*
G01X28000Y1739229D02*
X20901D01*
G01X27877Y1740629D02*
X20899D01*
G01X30727Y1739710D02*
X28000Y1739229D01*
G01X30178Y1741035D02*
X27877Y1740629D01*
G01X33228Y1741461D02*
X30727Y1739710D01*
G01X32222Y1742467D02*
X30178Y1741035D01*
G01X37338Y1747330D02*
X33228Y1741461D01*
G01X36013Y1747879D02*
X32222Y1742467D01*
G01X56642Y1856855D02*
X37338Y1747330D01*
G01X55317Y1857404D02*
X36013Y1747879D01*
G01X27877Y1740629D02*
X20899D01*
G01X28000Y1739229D02*
X20901D01*
G01X30178Y1741035D02*
X27877Y1740629D01*
G01X30727Y1739710D02*
X28000Y1739229D01*
G01X32222Y1742467D02*
X30178Y1741035D01*
G01X33228Y1741461D02*
X30727Y1739710D01*
G01X36013Y1747879D02*
X32222Y1742467D01*
G01X37338Y1747330D02*
X33228Y1741461D01*
G01X55317Y1857404D02*
X36013Y1747879D01*
G01X56642Y1856855D02*
X37338Y1747330D01*
G01X28000Y1726630D02*
X20901D01*
G01X27877Y1728030D02*
X20899D01*
G01X31229Y1727199D02*
X28000Y1726630D01*
G01X30680Y1728524D02*
X27877Y1728030D01*
G01X35109Y1729916D02*
X31229Y1727199D01*
G01X34103Y1730922D02*
X30680Y1728524D01*
G01X38894Y1735322D02*
X35109Y1729916D01*
G01X37569Y1735871D02*
X34103Y1730922D01*
G01X58712Y1855747D02*
X37569Y1735871D01*
G01X27877Y1728030D02*
X20899D01*
G01X28000Y1726630D02*
X20901D01*
G01X30680Y1728524D02*
X27877Y1728030D01*
G01X31229Y1727199D02*
X28000Y1726630D01*
G01X34103Y1730922D02*
X30680Y1728524D01*
G01X35109Y1729916D02*
X31229Y1727199D01*
G01X37569Y1735871D02*
X34103Y1730922D01*
G01X38894Y1735322D02*
X35109Y1729916D01*
G01X58712Y1855747D02*
X37569Y1735871D01*
G01X110732Y56302D02*
X117849Y61285D01*
G01X110183Y57627D02*
X112177Y59024D01*
G01X105297Y55344D02*
X110732Y56302D01*
G01X105174Y56744D02*
X110183Y57627D01*
G01X101000Y55344D02*
X105297D01*
G01X101000Y56744D02*
X105174D01*
G01X110732Y56302D02*
X117849Y61285D01*
G01X110732Y56302D02*
X117849Y61285D01*
G01X110183Y57627D02*
X112177Y59024D01*
G01X110732Y56302D02*
X117849Y61285D01*
G01X105174Y56744D02*
X110183Y57627D01*
G01X105297Y55344D02*
X110732Y56302D01*
G01X101000Y56744D02*
X105174D01*
G01X101000Y55344D02*
X105297D01*
G01X104143Y73978D02*
X115881Y76047D01*
G01X110256Y76478D02*
X115331Y77373D01*
G01X104020Y75378D02*
X106878Y75883D01*
G01X100836Y73978D02*
X104143D01*
G01X101164Y75378D02*
X104020D01*
G01X110256Y76478D02*
X115331Y77373D01*
G01X104143Y73978D02*
X115881Y76047D01*
G01X104020Y75378D02*
X106878Y75883D01*
G01X104143Y73978D02*
X115881Y76047D01*
G01X101164Y75378D02*
X104020D01*
G01X100836Y73978D02*
X104143D01*
G01X104210Y93039D02*
X100999D01*
G01X104087Y94439D02*
X101001D01*
G01X112607Y94519D02*
X104210Y93039D01*
G01X112058Y95844D02*
X104087Y94439D01*
G01D02*
X101001D01*
G01X104210Y93039D02*
X100999D01*
G01X112058Y95844D02*
X104087Y94439D01*
G01X112607Y94519D02*
X104210Y93039D01*
G01X106607Y143433D02*
X101000D01*
G01X106484Y144833D02*
X101000D01*
G01X107977Y143674D02*
X106607Y143433D01*
G01X113334Y146041D02*
X106484Y144833D01*
G01X113883Y144716D02*
X107977Y143674D01*
G01X113334Y146041D02*
X106484Y144833D01*
G01D02*
X101000D01*
G01X106607Y143433D02*
X101000D01*
G01X113334Y146041D02*
X106484Y144833D01*
G01X107977Y143674D02*
X106607Y143433D01*
G01X113883Y144716D02*
X107977Y143674D01*
G01X111069Y262500D02*
X70534Y320377D01*
G01X109744Y261951D02*
X69253Y319764D01*
G01X135898Y121694D02*
X111069Y262500D01*
G01X134477Y121688D02*
X109744Y261951D01*
G01D02*
X69253Y319764D01*
G01X111069Y262500D02*
X70534Y320377D01*
G01X134477Y121688D02*
X109744Y261951D01*
G01X135898Y121694D02*
X111069Y262500D01*
G01X107672Y259633D02*
X131164Y126390D01*
G01X106347Y259084D02*
X124803Y154403D01*
G01X66955Y317781D02*
X107672Y259633D01*
G01X65630Y317232D02*
X106347Y259084D01*
G01X107672Y259633D02*
X131164Y126390D01*
G01X107672Y259633D02*
X131164Y126390D01*
G01X107672Y259633D02*
X131164Y126390D01*
G01X107672Y259633D02*
X131164Y126390D01*
G01X106347Y259084D02*
X124803Y154403D01*
G01X107672Y259633D02*
X131164Y126390D01*
G01X65630Y317232D02*
X106347Y259084D01*
G01X66955Y317781D02*
X107672Y259633D01*
G01X104184Y257044D02*
X121093Y161136D01*
G01X111192Y209224D02*
X113970Y193468D01*
G01X102859Y256495D02*
X111192Y209224D01*
G01X104184Y257044D02*
X121093Y161136D01*
G01X104184Y257044D02*
X121093Y161136D01*
G01X111192Y209224D02*
X113970Y193468D01*
G01X104184Y257044D02*
X121093Y161136D01*
G01X102859Y256495D02*
X111192Y209224D01*
G01X104184Y257044D02*
X121093Y161136D01*
G01X91320Y336345D02*
X87325Y342049D01*
G01X90314Y335339D02*
X86000Y341500D01*
G01X116170Y318945D02*
X91320Y336345D01*
G01X115621Y317620D02*
X90314Y335339D01*
G01D02*
X86000Y341500D01*
G01X91320Y336345D02*
X87325Y342049D01*
G01X115621Y317620D02*
X90314Y335339D01*
G01X116170Y318945D02*
X91320Y336345D01*
G01X106295Y308458D02*
X116694Y301176D01*
G01X105392Y307381D02*
X116019Y299939D01*
G01X100963Y313790D02*
X106295Y308458D01*
G01X99886Y312887D02*
X105392Y307381D01*
G01X84325Y337549D02*
X100963Y313790D01*
G01X83000Y337000D02*
X99886Y312887D01*
G01X81953Y351004D02*
X84325Y337549D01*
G01X80573Y350761D02*
X83000Y337000D01*
G01X105392Y307381D02*
X116019Y299939D01*
G01X106295Y308458D02*
X116694Y301176D01*
G01X99886Y312887D02*
X105392Y307381D01*
G01X100963Y313790D02*
X106295Y308458D01*
G01X83000Y337000D02*
X99886Y312887D01*
G01X84325Y337549D02*
X100963Y313790D01*
G01X80573Y350761D02*
X83000Y337000D01*
G01X81953Y351004D02*
X84325Y337549D01*
G01X81953Y351004D02*
X84325Y337549D01*
G01X111256Y291722D02*
X129712Y278799D01*
G01X129163Y277474D02*
X110250Y290716D01*
G01X81146Y334724D02*
X111256Y291722D01*
G01X110250Y290716D02*
X79821Y334175D01*
G01X78247Y351170D02*
X81146Y334724D01*
G01X79821Y334175D02*
X76825Y351170D01*
G01X79821Y334175D02*
X76825Y351170D01*
G01X78247D02*
X81146Y334724D01*
G01X110250Y290716D02*
X79821Y334175D01*
G01X81146Y334724D02*
X111256Y291722D01*
G01X129163Y277474D02*
X110250Y290716D01*
G01X111256Y291722D02*
X129712Y278799D01*
G01X77825Y333049D02*
X74621Y351219D01*
G01X76500Y332500D02*
X73199Y351219D01*
G01X119577Y273420D02*
X77825Y333049D01*
G01X118252Y272871D02*
X76500Y332500D01*
G01D02*
X73199Y351219D01*
G01X77825Y333049D02*
X74621Y351219D01*
G01X118252Y272871D02*
X76500Y332500D01*
G01X119577Y273420D02*
X77825Y333049D01*
G01X74134Y323170D02*
X48450Y468820D01*
G01X72808Y322622D02*
X47028Y468820D01*
G01X114589Y265393D02*
X74134Y323170D01*
G01X113264Y264844D02*
X72808Y322622D01*
G01D02*
X47028Y468820D01*
G01X74134Y323170D02*
X48450Y468820D01*
G01X113264Y264844D02*
X72808Y322622D01*
G01X114589Y265393D02*
X74134Y323170D01*
G01X70009Y321906D02*
X44242Y468033D01*
G01X68630Y321663D02*
X42820Y468033D01*
G01X68726Y321117D02*
X68630Y321663D01*
G01X70080Y321504D02*
X70009Y321906D01*
G01X68630Y321663D02*
X42820Y468033D01*
G01X68726Y321117D02*
X68630Y321663D01*
G01X70534Y320377D02*
X70080Y321504D01*
G01X69255Y319803D02*
X68726Y321117D01*
G01X68630Y321663D02*
X42820Y468033D01*
G01X70009Y321906D02*
X44242Y468033D01*
G01X70080Y321504D02*
X70009Y321906D01*
G01X68726Y321117D02*
X68630Y321663D01*
G01X70009Y321906D02*
X44242Y468033D01*
G01X70080Y321504D02*
X70009Y321906D01*
G01X69255Y319803D02*
X68726Y321117D01*
G01X70534Y320377D02*
X70080Y321504D01*
G01X40541Y467559D02*
X66955Y317781D01*
G01X39119Y467559D02*
X65630Y317232D01*
G01X39119Y467559D02*
X65630Y317232D01*
G01X40541Y467559D02*
X66955Y317781D01*
G01X100387Y378562D02*
X159881Y389056D01*
G01X99838Y379887D02*
X159332Y390381D01*
G01X94244Y374261D02*
X100387Y378562D01*
G01X93238Y375267D02*
X99838Y379887D01*
G01X88211Y365644D02*
X94244Y374261D01*
G01X86886Y366195D02*
X93238Y375267D01*
G01X85688Y351339D02*
X88211Y365644D01*
G01X84266Y351337D02*
X86886Y366195D01*
G01X87325Y342049D02*
X85688Y351339D01*
G01X86000Y341500D02*
X84266Y351337D01*
G01X99838Y379887D02*
X159332Y390381D01*
G01X100387Y378562D02*
X159881Y389056D01*
G01X93238Y375267D02*
X99838Y379887D01*
G01X94244Y374261D02*
X100387Y378562D01*
G01X86886Y366195D02*
X93238Y375267D01*
G01X88211Y365644D02*
X94244Y374261D01*
G01X84266Y351337D02*
X86886Y366195D01*
G01X85688Y351339D02*
X88211Y365644D01*
G01X86000Y341500D02*
X84266Y351337D01*
G01X87325Y342049D02*
X85688Y351339D01*
G01X80531Y351004D02*
X80573Y350761D01*
G01X84829Y367314D02*
X81953Y351004D01*
G01X83504Y367863D02*
X80531Y351004D01*
G01X91362Y376643D02*
X84829Y367314D01*
G01X90356Y377649D02*
X83504Y367863D01*
G01X99738Y382508D02*
X91362Y376643D01*
G01X99189Y383833D02*
X90356Y377649D01*
G01X158639Y392887D02*
X99738Y382508D01*
G01X158090Y394212D02*
X99189Y383833D01*
G01X80531Y351004D02*
X80573Y350761D01*
G01X83504Y367863D02*
X80531Y351004D01*
G01X84829Y367314D02*
X81953Y351004D01*
G01X90356Y377649D02*
X83504Y367863D01*
G01X91362Y376643D02*
X84829Y367314D01*
G01X99189Y383833D02*
X90356Y377649D01*
G01X99738Y382508D02*
X91362Y376643D01*
G01X158090Y394212D02*
X99189Y383833D01*
G01X158639Y392887D02*
X99738Y382508D01*
G01X81303Y368496D02*
X78247Y351170D01*
G01X76825D02*
X79978Y369045D01*
G01X89006Y379494D02*
X81303Y368496D01*
G01X79978Y369045D02*
X88000Y380500D01*
G01X98607Y386217D02*
X89006Y379494D01*
G01X88000Y380500D02*
X98058Y387542D01*
G01X157052Y396526D02*
X98607Y386217D01*
G01X98058Y387542D02*
X156503Y397851D01*
G01X98058Y387542D02*
X156503Y397851D01*
G01X157052Y396526D02*
X98607Y386217D01*
G01X88000Y380500D02*
X98058Y387542D01*
G01X98607Y386217D02*
X89006Y379494D01*
G01X79978Y369045D02*
X88000Y380500D01*
G01X89006Y379494D02*
X81303Y368496D01*
G01X76825Y351170D02*
X79978Y369045D01*
G01X81303Y368496D02*
X78247Y351170D01*
G01X97366Y389750D02*
X155903Y400072D01*
G01X96817Y391075D02*
X155354Y401397D01*
G01X95156Y388202D02*
X97366Y389750D01*
G01X94353Y389350D02*
X96817Y391075D01*
G01X85541Y381469D02*
X95156Y388202D01*
G01X84535Y382475D02*
X94353Y389350D01*
G01X78077Y370812D02*
X85541Y381469D01*
G01X76752Y371361D02*
X84535Y382475D01*
G01X74621Y351219D02*
X78077Y370812D01*
G01X73199Y351219D02*
X76752Y371361D01*
G01X96817Y391075D02*
X155354Y401397D01*
G01X97366Y389750D02*
X155903Y400072D01*
G01X94353Y389350D02*
X96817Y391075D01*
G01X95156Y388202D02*
X97366Y389750D01*
G01X84535Y382475D02*
X94353Y389350D01*
G01X85541Y381469D02*
X95156Y388202D01*
G01X76752Y371361D02*
X84535Y382475D01*
G01X78077Y370812D02*
X85541Y381469D01*
G01X73199Y351219D02*
X76752Y371361D01*
G01X74621Y351219D02*
X78077Y370812D01*
G01X48450Y468820D02*
X63499Y554159D01*
G01X47028Y468820D02*
X62077Y554159D01*
G01X47028Y468820D02*
X62077Y554159D01*
G01X48450Y468820D02*
X63499Y554159D01*
G01X108827Y461479D02*
X119268Y468787D01*
G01X108278Y462804D02*
X113855Y466708D01*
G01X104730Y460756D02*
X108827Y461479D01*
G01X104607Y462156D02*
X108278Y462804D01*
G01X101000Y460756D02*
X104730D01*
G01X101000Y462156D02*
X104607D01*
G01X108827Y461479D02*
X119268Y468787D01*
G01X108827Y461479D02*
X119268Y468787D01*
G01X108278Y462804D02*
X113855Y466708D01*
G01X108827Y461479D02*
X119268Y468787D01*
G01X104607Y462156D02*
X108278Y462804D01*
G01X104730Y460756D02*
X108827Y461479D01*
G01X101000Y462156D02*
X104607D01*
G01X101000Y460756D02*
X104730D01*
G01X44242Y468033D02*
X59495Y554529D01*
G01X42820Y468033D02*
X58073Y554529D01*
G01X105064Y479653D02*
X100999D01*
G01X101001Y481053D02*
X104941D01*
G01X108219Y480209D02*
X105064Y479653D01*
G01X104941Y481053D02*
X107670Y481534D01*
G01X121039Y489187D02*
X108219Y480209D01*
G01X107670Y481534D02*
X109267Y482653D01*
G01X121039Y489187D02*
X108219Y480209D01*
G01X121039Y489187D02*
X108219Y480209D01*
G01X107670Y481534D02*
X109267Y482653D01*
G01X121039Y489187D02*
X108219Y480209D01*
G01X104941Y481053D02*
X107670Y481534D01*
G01X108219Y480209D02*
X105064Y479653D01*
G01X101001Y481053D02*
X104941D01*
G01X105064Y479653D02*
X100999D01*
G01X42820Y468033D02*
X58073Y554529D01*
G01X44242Y468033D02*
X59495Y554529D01*
G01X55686Y553449D02*
X40541Y467559D01*
G01X54264Y553449D02*
X39119Y467559D01*
G01X54264Y553449D02*
X39119Y467559D01*
G01X55686Y553449D02*
X40541Y467559D01*
G01X63499Y554159D02*
X49945Y631022D01*
G01X62077Y554159D02*
X48620Y630473D01*
G01X62077Y554159D02*
X48620Y630473D01*
G01X63499Y554159D02*
X49945Y631022D01*
G01X59495Y554529D02*
X47529Y622388D01*
G01X58073Y554529D02*
X46204Y621839D01*
G01X111046Y484802D02*
X112077Y484620D01*
G01X111046Y484802D02*
X112077Y484620D01*
G01X110335Y499575D02*
X114506Y502494D01*
G01X113500Y503500D02*
X109786Y500900D01*
G01X104525Y498551D02*
X110335Y499575D01*
G01X109786Y500900D02*
X104402Y499951D01*
G01X100999Y498551D02*
X104525D01*
G01X104402Y499951D02*
X101001D01*
G01X104402D02*
X101001D01*
G01X100999Y498551D02*
X104525D01*
G01X109786Y500900D02*
X104402Y499951D01*
G01X104525Y498551D02*
X110335Y499575D01*
G01X113500Y503500D02*
X109786Y500900D01*
G01X110335Y499575D02*
X114506Y502494D01*
G01X79432Y553574D02*
X82530Y571128D01*
G01X79432Y553574D02*
X82530Y571128D01*
G01X80873Y553680D02*
X81212Y555600D01*
G01X79432Y553574D02*
X82530Y571128D01*
G01X82305Y549386D02*
X80873Y553680D01*
G01X81031Y548778D02*
X79432Y553574D01*
G01X84156Y546494D02*
X82305Y549386D01*
G01X83124Y545509D02*
X81031Y548778D01*
G01X86492Y544839D02*
X84156Y546494D01*
G01X85924Y543524D02*
X83124Y545509D01*
G01X98033Y542510D02*
X86492Y544839D01*
G01X98100Y541068D02*
X85924Y543524D01*
G01X102009Y543705D02*
X98033Y542510D01*
G01X102580Y542414D02*
X98100Y541068D01*
G01X103897Y544838D02*
X102009Y543705D01*
G01X104926Y543822D02*
X102580Y542414D01*
G01X104800Y546385D02*
X103897Y544838D01*
G01X106200Y546006D02*
X104926Y543822D01*
G01X104800Y547800D02*
Y546385D01*
G01X106200Y548380D02*
Y546006D01*
G01X103800Y548800D02*
X104800Y547800D01*
G01X104380Y550200D02*
X106200Y548380D01*
G01X100855Y548800D02*
X103800D01*
G01X101145Y550200D02*
X104380D01*
G01X79432Y553574D02*
X82530Y571128D01*
G01X80873Y553680D02*
X81212Y555600D01*
G01X81031Y548778D02*
X79432Y553574D01*
G01X82305Y549386D02*
X80873Y553680D01*
G01X83124Y545509D02*
X81031Y548778D01*
G01X84156Y546494D02*
X82305Y549386D01*
G01X85924Y543524D02*
X83124Y545509D01*
G01X86492Y544839D02*
X84156Y546494D01*
G01X98100Y541068D02*
X85924Y543524D01*
G01X98033Y542510D02*
X86492Y544839D01*
G01X102580Y542414D02*
X98100Y541068D01*
G01X102009Y543705D02*
X98033Y542510D01*
G01X104926Y543822D02*
X102580Y542414D01*
G01X103897Y544838D02*
X102009Y543705D01*
G01X106200Y546006D02*
X104926Y543822D01*
G01X104800Y546385D02*
X103897Y544838D01*
G01X106200Y548380D02*
Y546006D01*
G01X104800Y547800D02*
Y546385D01*
G01X104380Y550200D02*
X106200Y548380D01*
G01X103800Y548800D02*
X104800Y547800D01*
G01X101145Y550200D02*
X104380D01*
G01X100855Y548800D02*
X103800D01*
G01X58073Y554529D02*
X46204Y621839D01*
G01X59495Y554529D02*
X47529Y622388D01*
G01X46852Y603543D02*
X55686Y553449D01*
G01X45527Y602994D02*
X54264Y553449D01*
G01X45527Y602994D02*
X54264Y553449D01*
G01X46852Y603543D02*
X55686Y553449D01*
G01X43479Y600669D02*
X51855Y553163D01*
G01X50094Y555083D02*
X50433Y553163D01*
G01X50094Y555083D02*
X50433Y553163D01*
G01X43479Y600669D02*
X51855Y553163D01*
G01X43479Y600669D02*
X51855Y553163D01*
G01X43479Y600669D02*
X51855Y553163D01*
G01X43479Y600669D02*
X51855Y553163D01*
G01X43479Y600669D02*
X51855Y553163D01*
G01X43479Y600669D02*
X51855Y553163D01*
G01X43479Y600669D02*
X51855Y553163D01*
G01X115159Y593326D02*
X101615Y670121D01*
G01X113950Y592113D02*
X100290Y669572D01*
G01X113950Y592113D02*
X100290Y669572D01*
G01X113950Y592113D02*
X100290Y669572D01*
G01X115159Y593326D02*
X101615Y670121D01*
G01X41271Y626760D02*
X40240Y626578D01*
G01X44190Y624715D02*
X41271Y626760D01*
G01X47529Y622388D02*
X45196Y625721D01*
G01X46204Y621839D02*
X44190Y624715D01*
G01X111530Y591656D02*
X122991Y575286D01*
G01X121666Y574737D02*
X110205Y591107D01*
G01X98098Y667803D02*
X111530Y591656D01*
G01X110205Y591107D02*
X96773Y667254D01*
G01X110205Y591107D02*
X96773Y667254D01*
G01X98098Y667803D02*
X111530Y591656D01*
G01X121666Y574737D02*
X110205Y591107D01*
G01X111530Y591656D02*
X122991Y575286D01*
G01X107826Y590375D02*
X94396Y666519D01*
G01X99732Y628204D02*
X106501Y589826D01*
G01X93071Y665970D02*
X99732Y628204D01*
G01X119258Y574046D02*
X107826Y590375D01*
G01X110644Y583908D02*
X111762Y582311D01*
G01X106501Y589826D02*
X108677Y586718D01*
G01X119258Y574046D02*
X107826Y590375D01*
G01X119258Y574046D02*
X107826Y590375D01*
G01X110644Y583908D02*
X111762Y582311D01*
G01X119258Y574046D02*
X107826Y590375D01*
G01X106501Y589826D02*
X108677Y586718D01*
G01X119258Y574046D02*
X107826Y590375D01*
G01X99732Y628204D02*
X106501Y589826D01*
G01X107826Y590375D02*
X94396Y666519D01*
G01X93071Y665970D02*
X99732Y628204D01*
G01X107826Y590375D02*
X94396Y666519D01*
G01X101451Y605671D02*
X91252Y663511D01*
G01X100029Y605671D02*
X89927Y662962D01*
G01X101074Y603533D02*
X101451Y605671D01*
G01X96429Y585255D02*
X100029Y605671D01*
G01X100140Y598235D02*
X100479Y600155D01*
G01X96429Y585255D02*
X100029Y605671D01*
G01X97754Y584706D02*
X99544Y594857D01*
G01X96429Y585255D02*
X100029Y605671D01*
G01X93174Y578163D02*
X97754Y584706D01*
G01X92168Y579169D02*
X96429Y585255D01*
G01X85311Y572657D02*
X93174Y578163D01*
G01X84305Y573663D02*
X92168Y579169D01*
G01X83855Y570579D02*
X85311Y572657D01*
G01X82530Y571128D02*
X84305Y573663D01*
G01X82743Y564276D02*
X83855Y570579D01*
G01X81808Y558978D02*
X82147Y560898D01*
G01X100029Y605671D02*
X89927Y662962D01*
G01X101451Y605671D02*
X91252Y663511D01*
G01X96429Y585255D02*
X100029Y605671D01*
G01X101074Y603533D02*
X101451Y605671D01*
G01X100140Y598235D02*
X100479Y600155D01*
G01X97754Y584706D02*
X99544Y594857D01*
G01X92168Y579169D02*
X96429Y585255D01*
G01X93174Y578163D02*
X97754Y584706D01*
G01X84305Y573663D02*
X92168Y579169D01*
G01X85311Y572657D02*
X93174Y578163D01*
G01X82530Y571128D02*
X84305Y573663D01*
G01X83855Y570579D02*
X85311Y572657D01*
G01X82743Y564276D02*
X83855Y570579D01*
G01X81808Y558978D02*
X82147Y560898D01*
G01X41271Y626760D02*
X40240Y626578D01*
G01X44190Y624715D02*
X41271Y626760D01*
G01X46204Y621839D02*
X44190Y624715D01*
G01X47529Y622388D02*
X45196Y625721D01*
G01X40681Y609913D02*
X45527Y602994D01*
G01X40681Y609913D02*
X45527Y602994D01*
G01X49160Y560381D02*
X49499Y558461D01*
G01X45035Y583772D02*
X48565Y563759D01*
G01X44101Y589070D02*
X44440Y587150D01*
G01X43167Y594368D02*
X43506Y592448D01*
G01X42298Y599300D02*
X42569Y597759D01*
G01X42153Y600120D02*
X42298Y599300D01*
G01X39429Y606458D02*
X43479Y600669D01*
G01X49160Y560381D02*
X49499Y558461D01*
G01X45035Y583772D02*
X48565Y563759D01*
G01X44101Y589070D02*
X44440Y587150D01*
G01X43167Y594368D02*
X43506Y592448D01*
G01X42298Y599300D02*
X42569Y597759D01*
G01X42153Y600120D02*
X42298Y599300D01*
G01X39429Y606458D02*
X43479Y600669D01*
G01X113772Y696621D02*
X48754Y789477D01*
G01X112766Y695615D02*
X47748Y788471D01*
G01X112766Y695615D02*
X47748Y788471D01*
G01X113772Y696621D02*
X48754Y789477D01*
G01X121551Y678870D02*
X55812Y772756D01*
G01X120226Y678321D02*
X54806Y771750D01*
G01X120226Y678321D02*
X54806Y771750D01*
G01X121551Y678870D02*
X55812Y772756D01*
G01X116785Y677670D02*
X78507Y732346D01*
G01X115460Y677121D02*
X77501Y731340D01*
G01X115460Y677121D02*
X77501Y731340D01*
G01X116785Y677670D02*
X78507Y732346D01*
G01X86181Y714376D02*
X113327Y675608D01*
G01X85175Y713370D02*
X112002Y675059D01*
G01X85175Y713370D02*
X112002Y675059D01*
G01X86181Y714376D02*
X113327Y675608D01*
G01X109814Y673982D02*
X123595Y595849D01*
G01X122270Y595300D02*
X108489Y673433D01*
G01X88254Y704771D02*
X109814Y673982D01*
G01X108489Y673433D02*
X87248Y703765D01*
G01X108489Y673433D02*
X87248Y703765D01*
G01X88254Y704771D02*
X109814Y673982D01*
G01X122270Y595300D02*
X108489Y673433D01*
G01X109814Y673982D02*
X123595Y595849D01*
G01X98488Y683304D02*
X69861Y703350D01*
G01X97482Y682298D02*
X69312Y702025D01*
G01X106172Y672328D02*
X98488Y683304D01*
G01X104847Y671779D02*
X97482Y682298D01*
G01X119889Y594511D02*
X106172Y672328D01*
G01X118564Y593962D02*
X104847Y671779D01*
G01X97482Y682298D02*
X69312Y702025D01*
G01X98488Y683304D02*
X69861Y703350D01*
G01X104847Y671779D02*
X97482Y682298D01*
G01X106172Y672328D02*
X98488Y683304D01*
G01X118564Y593962D02*
X104847Y671779D01*
G01X119889Y594511D02*
X106172Y672328D01*
G01X49945Y631022D02*
X42978Y640974D01*
G01X48620Y630473D02*
X41972Y639968D01*
G01X48620Y630473D02*
X41972Y639968D01*
G01X49945Y631022D02*
X42978Y640974D01*
G01X76760Y688113D02*
X43894Y693907D01*
G01X98462Y674625D02*
X77309Y689438D01*
G01X97456Y673619D02*
X76760Y688113D01*
G01X101615Y670121D02*
X98462Y674625D01*
G01X100290Y669572D02*
X97456Y673619D01*
G01X76760Y688113D02*
X43894Y693907D01*
G01X97456Y673619D02*
X76760Y688113D01*
G01X98462Y674625D02*
X77309Y689438D01*
G01X100290Y669572D02*
X97456Y673619D01*
G01X101615Y670121D02*
X98462Y674625D01*
G01X95506Y671506D02*
X98098Y667803D01*
G01X96773Y667254D02*
X94500Y670499D01*
G01X95304Y671647D02*
X95506Y671506D01*
G01X94500Y670500D02*
X90162Y673539D01*
G01X95029Y671839D02*
X95304Y671647D01*
G01X94500Y670500D02*
X90162Y673539D01*
G01X90711Y674864D02*
X95029Y671839D01*
G01X94500Y670500D02*
X90162Y673539D01*
G01X42584Y681927D02*
X40664Y682266D01*
G01X47882Y680993D02*
X45962Y681332D01*
G01X90162Y673539D02*
X51260Y680398D01*
G01X42584Y681927D02*
X40664Y682266D01*
G01X47882Y680993D02*
X45962Y681332D01*
G01X90162Y673539D02*
X51260Y680398D01*
G01X94500Y670500D02*
X90162Y673539D01*
G01X95304Y671647D02*
X95506Y671506D01*
G01X95029Y671839D02*
X95304Y671647D01*
G01X90711Y674864D02*
X95029Y671839D01*
G01X96773Y667254D02*
X94500Y670499D01*
G01X95506Y671506D02*
X98098Y667803D01*
G01X53636Y675989D02*
X53976Y675942D01*
G01X51716Y675650D02*
X53636Y675989D01*
G01X46417Y674716D02*
X48338Y675055D01*
G01X41119Y673782D02*
X43039Y674121D01*
G01X54194Y677326D02*
X53610Y677407D01*
G01X53976Y675942D02*
X88685Y669821D01*
G01X53636Y675989D02*
X53976Y675942D01*
G01X51716Y675650D02*
X53636Y675989D01*
G01X89234Y671146D02*
X54194Y677326D01*
G01X53976Y675942D02*
X88685Y669821D01*
G01X53636Y675989D02*
X53976Y675942D01*
G01X93006Y668506D02*
X89234Y671146D01*
G01X90344Y668660D02*
X92000Y667500D01*
G01X88685Y669821D02*
X90344Y668660D01*
G01X93148Y668304D02*
X93006Y668506D01*
G01X92000Y667500D02*
X93071Y665970D01*
G01X94396Y666519D02*
X93147Y668303D01*
G01X92000Y667500D02*
X93071Y665970D01*
G01X92000Y667500D02*
X93071Y665970D01*
G01X93148Y668304D02*
X93006Y668506D01*
G01X94396Y666519D02*
X93147Y668303D01*
G01X90344Y668660D02*
X92000Y667500D01*
G01X93006Y668506D02*
X89234Y671146D01*
G01X88685Y669821D02*
X90344Y668660D01*
G01X93006Y668506D02*
X89234Y671146D01*
G01X53976Y675942D02*
X88685Y669821D01*
G01X54194Y677326D02*
X53610Y677407D01*
G01X89234Y671146D02*
X54194Y677326D01*
G01X53636Y675989D02*
X53976Y675942D01*
G01X54194Y677326D02*
X53610Y677407D01*
G01X89234Y671146D02*
X54194Y677326D01*
G01X51716Y675650D02*
X53636Y675989D01*
G01X54194Y677326D02*
X53610Y677407D01*
G01X46417Y674716D02*
X48338Y675055D01*
G01X41119Y673782D02*
X43039Y674121D01*
G01X44400Y665435D02*
X42480Y665096D01*
G01X72450Y668957D02*
X43029Y663771D01*
G01X49698Y666369D02*
X47778Y666030D01*
G01X72450Y668957D02*
X43029Y663771D01*
G01X54996Y667303D02*
X53076Y666964D01*
G01X72450Y668957D02*
X43029Y663771D01*
G01X60294Y668237D02*
X58374Y667898D01*
G01X72450Y668957D02*
X43029Y663771D01*
G01X72448Y670380D02*
X63672Y668832D01*
G01X72450Y668957D02*
X43029Y663771D01*
G01X86902Y667829D02*
X72448Y670380D01*
G01X86353Y666504D02*
X72450Y668957D01*
G01X89506Y666006D02*
X86902Y667829D01*
G01X88500Y665000D02*
X86353Y666504D01*
G01X91252Y663511D02*
X89506Y666006D01*
G01X89927Y662962D02*
X88500Y665000D01*
G01X72450Y668957D02*
X43029Y663771D01*
G01X44400Y665435D02*
X42480Y665096D01*
G01X49698Y666369D02*
X47778Y666030D01*
G01X54996Y667303D02*
X53076Y666964D01*
G01X60294Y668237D02*
X58374Y667898D01*
G01X72448Y670380D02*
X63672Y668832D01*
G01X86353Y666504D02*
X72450Y668957D01*
G01X86902Y667829D02*
X72448Y670380D01*
G01X88500Y665000D02*
X86353Y666504D01*
G01X89506Y666006D02*
X86902Y667829D01*
G01X89927Y662962D02*
X88500Y665000D01*
G01X91252Y663511D02*
X89506Y666006D01*
G01X109936Y725555D02*
X88788Y746703D01*
G01X109258Y724252D02*
X87711Y745800D01*
G01X139488Y720346D02*
X109936Y725555D01*
G01X139365Y718946D02*
X109258Y724252D01*
G01D02*
X87711Y745800D01*
G01X109936Y725555D02*
X88788Y746703D01*
G01X139365Y718946D02*
X109258Y724252D01*
G01X139488Y720346D02*
X109936Y725555D01*
G01X107215Y713199D02*
X118899Y705018D01*
G01X106209Y712193D02*
X118350Y703693D01*
G01X42518Y805598D02*
X107215Y713199D01*
G01X41511Y804594D02*
X106209Y712193D01*
G01D02*
X118350Y703693D01*
G01X107215Y713199D02*
X118899Y705018D01*
G01X41511Y804594D02*
X106209Y712193D01*
G01X42518Y805598D02*
X107215Y713199D01*
G01X73107Y715377D02*
X88254Y704771D01*
G01X87248Y703765D02*
X72558Y714052D01*
G01X87248Y703765D02*
X72558Y714052D01*
G01X73107Y715377D02*
X88254Y704771D01*
G01X65314Y809965D02*
X56775Y858393D01*
G01X65314Y809965D02*
X56775Y858393D01*
G01X60643Y844523D02*
X60304Y846443D01*
G01X65314Y809965D02*
X56775Y858393D01*
G01X61577Y839225D02*
X61238Y841145D01*
G01X65314Y809965D02*
X56775Y858393D01*
G01X66639Y810514D02*
X62172Y835847D01*
G01X65314Y809965D02*
X56775Y858393D01*
G01X74894Y798725D02*
X66639Y810514D01*
G01X73888Y797719D02*
X65314Y809965D01*
G01X79500Y795500D02*
X74894Y798725D01*
G01X78951Y794175D02*
X73888Y797719D01*
G01X90419Y793575D02*
X79500Y795500D01*
G01X90419Y792153D02*
X78951Y794175D01*
G01X130330Y800613D02*
X90419Y793575D01*
G01X149755Y802617D02*
X90419Y792153D01*
G01X149755Y802617D02*
X90419Y792153D01*
G01X149755Y802617D02*
X90419Y792153D01*
G01X149755Y802617D02*
X90419Y792153D01*
G01X65314Y809965D02*
X56775Y858393D01*
G01X60643Y844523D02*
X60304Y846443D01*
G01X61577Y839225D02*
X61238Y841145D01*
G01X66639Y810514D02*
X62172Y835847D01*
G01X73888Y797719D02*
X65314Y809965D01*
G01X74894Y798725D02*
X66639Y810514D01*
G01X78951Y794175D02*
X73888Y797719D01*
G01X79500Y795500D02*
X74894Y798725D01*
G01X90419Y792153D02*
X78951Y794175D01*
G01X90419Y793575D02*
X79500Y795500D01*
G01X149755Y802617D02*
X90419Y792153D01*
G01X130330Y800613D02*
X90419Y793575D01*
G01X89414Y789722D02*
X151440Y800656D01*
G01X89414Y788300D02*
X151989Y799331D01*
G01X78411Y791662D02*
X89414Y789722D01*
G01X77862Y790337D02*
X89414Y788300D01*
G01X72383Y795883D02*
X78411Y791662D01*
G01X71377Y794877D02*
X77862Y790337D01*
G01X61079Y812026D02*
X72383Y795883D01*
G01X59754Y811477D02*
X71377Y794877D01*
G01X57545Y832067D02*
X61079Y812026D01*
G01X53417Y847413D02*
X59754Y811477D01*
G01X56611Y837366D02*
X56949Y835445D01*
G01X53417Y847413D02*
X59754Y811477D01*
G01X55676Y842664D02*
X56015Y840743D01*
G01X53417Y847413D02*
X59754Y811477D01*
G01X54742Y847962D02*
X55081Y846042D01*
G01X53417Y847413D02*
X59754Y811477D01*
G01X47757Y857928D02*
X54742Y847962D01*
G01X46751Y856922D02*
X53417Y847413D01*
G01X89414Y788300D02*
X151989Y799331D01*
G01X89414Y789722D02*
X151440Y800656D01*
G01X77862Y790337D02*
X89414Y788300D01*
G01X78411Y791662D02*
X89414Y789722D01*
G01X71377Y794877D02*
X77862Y790337D01*
G01X72383Y795883D02*
X78411Y791662D01*
G01X59754Y811477D02*
X71377Y794877D01*
G01X61079Y812026D02*
X72383Y795883D01*
G01X53417Y847413D02*
X59754Y811477D01*
G01X57545Y832067D02*
X61079Y812026D01*
G01X56611Y837366D02*
X56949Y835445D01*
G01X55676Y842664D02*
X56015Y840743D01*
G01X54742Y847962D02*
X55081Y846042D01*
G01X46751Y856922D02*
X53417Y847413D01*
G01X47757Y857928D02*
X54742Y847962D01*
G01X45567Y846403D02*
X39957Y850331D01*
G01X44561Y845397D02*
X39408Y849006D01*
G01X52893Y835939D02*
X45567Y846403D01*
G01X51568Y835390D02*
X44561Y845397D01*
G01X57311Y810909D02*
X52893Y835939D01*
G01X55986Y810360D02*
X51568Y835390D01*
G01X69706Y793207D02*
X57311Y810909D01*
G01X68700Y792201D02*
X55986Y810360D01*
G01X76630Y788359D02*
X69706Y793207D01*
G01X76081Y787034D02*
X68700Y792201D01*
G01X90166Y785971D02*
X76630Y788359D01*
G01X90166Y784549D02*
X76081Y787034D01*
G01X153298Y797107D02*
X90166Y785971D01*
G01X153847Y795782D02*
X90166Y784549D01*
G01X44561Y845397D02*
X39408Y849006D01*
G01X45567Y846403D02*
X39957Y850331D01*
G01X51568Y835390D02*
X44561Y845397D01*
G01X52893Y835939D02*
X45567Y846403D01*
G01X55986Y810360D02*
X51568Y835390D01*
G01X57311Y810909D02*
X52893Y835939D01*
G01X68700Y792201D02*
X55986Y810360D01*
G01X69706Y793207D02*
X57311Y810909D01*
G01X76081Y787034D02*
X68700Y792201D01*
G01X76630Y788359D02*
X69706Y793207D01*
G01X90166Y784549D02*
X76081Y787034D01*
G01X90166Y785971D02*
X76630Y788359D01*
G01X153847Y795782D02*
X90166Y784549D01*
G01X153298Y797107D02*
X90166Y785971D01*
G01X97550Y783627D02*
X155014Y793758D01*
G01X155563Y792433D02*
X97794Y782248D01*
G01X89415Y782193D02*
X97550Y783627D01*
G01X97794Y782248D02*
X89415Y780771D01*
G01X75601Y784628D02*
X89415Y782193D01*
G01Y780771D02*
X75052Y783303D01*
G01X66797Y790793D02*
X75601Y784628D01*
G01X75052Y783303D02*
X65791Y789787D01*
G01X53432Y809880D02*
X66797Y790793D01*
G01X65791Y789787D02*
X52107Y809331D01*
G01X51225Y822394D02*
X53432Y809880D01*
G01X52107Y809331D02*
X49900Y821845D01*
G01X47686Y827448D02*
X51225Y822394D01*
G01X49900Y821845D02*
X46680Y826442D01*
G01X43875Y830116D02*
X47686Y827448D01*
G01X41065Y832084D02*
X42096Y832266D01*
G01X39468Y833202D02*
X41065Y832084D01*
G01X43875Y830116D02*
X47686Y827448D01*
G01X41065Y832084D02*
X42096Y832266D01*
G01X39468Y833202D02*
X41065Y832084D01*
G01X49900Y821845D02*
X46680Y826442D01*
G01X47686Y827448D02*
X51225Y822394D01*
G01X52107Y809331D02*
X49900Y821845D01*
G01X51225Y822394D02*
X53432Y809880D01*
G01X65791Y789787D02*
X52107Y809331D01*
G01X53432Y809880D02*
X66797Y790793D01*
G01X75052Y783303D02*
X65791Y789787D01*
G01X66797Y790793D02*
X75601Y784628D01*
G01X89415Y780771D02*
X75052Y783303D01*
G01X75601Y784628D02*
X89415Y782193D01*
G01X97794Y782248D02*
X89415Y780771D01*
G01Y782193D02*
X97550Y783627D01*
G01X155563Y792433D02*
X97794Y782248D01*
G01X97550Y783627D02*
X155014Y793758D01*
G01X51516Y868348D02*
X41694Y875225D01*
G01X50510Y867342D02*
X41145Y873900D01*
G01X58100Y858942D02*
X51516Y868348D01*
G01X56775Y858393D02*
X50510Y867342D01*
G01X58774Y855119D02*
X58100Y858942D01*
G01X59709Y849821D02*
X59370Y851741D01*
G01X106146Y863874D02*
X113583Y854544D01*
G01X107192Y864808D02*
X114552Y855575D01*
G01X103520Y866500D02*
X106146Y863874D01*
G01X104100Y867900D02*
X107192Y864808D01*
G01X101232Y866500D02*
X103520D01*
G01X100768Y867900D02*
X104100D01*
G01X50510Y867342D02*
X41145Y873900D01*
G01X51516Y868348D02*
X41694Y875225D01*
G01X56775Y858393D02*
X50510Y867342D01*
G01X58100Y858942D02*
X51516Y868348D01*
G01X58774Y855119D02*
X58100Y858942D01*
G01X59709Y849821D02*
X59370Y851741D01*
G01X107192Y864808D02*
X114552Y855575D01*
G01X106146Y863874D02*
X113583Y854544D01*
G01X104100Y867900D02*
X107192Y864808D01*
G01X103520Y866500D02*
X106146Y863874D01*
G01X100768Y867900D02*
X104100D01*
G01X101232Y866500D02*
X103520D01*
G01X106546Y885165D02*
X100999D01*
G01X106669Y886565D02*
X101001D01*
G01X112995Y884028D02*
X106546Y885165D01*
G01X113544Y885353D02*
X106669Y886565D01*
G01X40839Y862775D02*
X47757Y857928D01*
G01X40290Y861450D02*
X46751Y856922D01*
G01X106669Y886565D02*
X101001D01*
G01X106546Y885165D02*
X100999D01*
G01X113544Y885353D02*
X106669Y886565D01*
G01X112995Y884028D02*
X106546Y885165D01*
G01X40290Y861450D02*
X46751Y856922D01*
G01X40839Y862775D02*
X47757Y857928D01*
G01X49867Y935840D02*
X39005Y920328D01*
G01X49867Y935840D02*
X39005Y920328D01*
G01X110787Y904359D02*
X136800Y886145D01*
G01X110787Y904359D02*
X136800Y886145D01*
G01X110787Y904359D02*
X136800Y886145D01*
G01X110787Y904359D02*
X136800Y886145D01*
G01X110787Y904359D02*
X136800Y886145D01*
G01X110787Y904359D02*
X136800Y886145D01*
G01X110237Y903034D02*
X111834Y901916D01*
G01X110787Y904359D02*
X136800Y886145D01*
G01X104402Y904063D02*
X110237Y903034D01*
G01X104525Y905463D02*
X110786Y904359D01*
G01X100999Y904063D02*
X104402D01*
G01X101001Y905463D02*
X104525D01*
G01X110787Y904359D02*
X136800Y886145D01*
G01X110237Y903034D02*
X111834Y901916D01*
G01X104525Y905463D02*
X110786Y904359D01*
G01X104402Y904063D02*
X110237Y903034D01*
G01X101001Y905463D02*
X104525D01*
G01X100999Y904063D02*
X104402D01*
G01X56141Y929998D02*
X39316Y905967D01*
G01X57466Y929449D02*
X40322Y904961D01*
G01X57466Y929449D02*
X40322Y904961D01*
G01X56141Y929998D02*
X39316Y905967D01*
G01X59879Y1000686D02*
X48542Y936389D01*
G01X61204Y1000137D02*
X49867Y935840D01*
G01X117681Y981884D02*
X80016Y1008253D01*
G01X116675Y980878D02*
X79467Y1006928D01*
G01X61204Y1000137D02*
X49867Y935840D01*
G01X59879Y1000686D02*
X48542Y936389D01*
G01X116675Y980878D02*
X79467Y1006928D01*
G01X117681Y981884D02*
X80016Y1008253D01*
G01X61590Y960900D02*
X56141Y929998D01*
G01X62920Y960376D02*
X57466Y929449D01*
G01X67815Y970484D02*
X61590Y960900D01*
G01X68828Y969471D02*
X62920Y960376D01*
G01X82323Y979906D02*
X67815Y970484D01*
G01X82868Y978590D02*
X68828Y969471D01*
G01X89207Y981370D02*
X82323Y979906D01*
G01X96129Y981410D02*
X82868Y978590D01*
G01X96129Y982842D02*
X89207Y981370D01*
G01X96129Y981410D02*
X82868Y978590D01*
G01X103428Y981290D02*
X96129Y982842D01*
G01X102883Y979974D02*
X96129Y981410D01*
G01X115746Y973290D02*
X103428Y981290D01*
G01X114755Y972264D02*
X102883Y979974D01*
G01X62920Y960376D02*
X57466Y929449D01*
G01X61590Y960900D02*
X56141Y929998D01*
G01X68828Y969471D02*
X62920Y960376D01*
G01X67815Y970484D02*
X61590Y960900D01*
G01X82868Y978590D02*
X68828Y969471D01*
G01X82323Y979906D02*
X67815Y970484D01*
G01X96129Y981410D02*
X82868Y978590D01*
G01X89207Y981370D02*
X82323Y979906D01*
G01X96129Y982842D02*
X89207Y981370D01*
G01X102883Y979974D02*
X96129Y981410D01*
G01X103428Y981290D02*
X96129Y982842D01*
G01X114755Y972264D02*
X102883Y979974D01*
G01X115746Y973290D02*
X103428Y981290D01*
G01X104941Y954457D02*
X101000D01*
G01Y955857D02*
X105064D01*
G01X106248Y954227D02*
X104941Y954457D01*
G01X105064Y955857D02*
X106797Y955552D01*
G01X108482Y952663D02*
X106248Y954227D01*
G01X106797Y955552D02*
X109488Y953669D01*
G01X109601Y951066D02*
X108482Y952663D01*
G01X109488Y953669D02*
X116281Y943968D01*
G01X109488Y953669D02*
X116281Y943968D01*
G01X109488Y953669D02*
X116281Y943968D01*
G01X109601Y951066D02*
X108482Y952663D01*
G01X106797Y955552D02*
X109488Y953669D01*
G01X108482Y952663D02*
X106248Y954227D01*
G01X105064Y955857D02*
X106797Y955552D01*
G01X106248Y954227D02*
X104941Y954457D01*
G01X101000Y955857D02*
X105064D01*
G01X104941Y954457D02*
X101000D01*
G01X107584Y1074378D02*
X119404Y1007345D01*
G01X106259Y1073829D02*
X118079Y1006796D01*
G01X106259Y1073829D02*
X118079Y1006796D01*
G01X107584Y1074378D02*
X119404Y1007345D01*
G01X105988Y1011437D02*
X130007Y977135D01*
G01X104663Y1010888D02*
X128682Y976586D01*
G01X96119Y1067418D02*
X105988Y1011437D01*
G01X94794Y1066868D02*
X104663Y1010888D01*
G01D02*
X128682Y976586D01*
G01X105988Y1011437D02*
X130007Y977135D01*
G01X94794Y1066868D02*
X104663Y1010888D01*
G01X96119Y1067418D02*
X105988Y1011437D01*
G01X93101Y1062984D02*
X86298Y1072700D01*
G01X91776Y1062434D02*
X85293Y1071694D01*
G01X102464Y1009902D02*
X93101Y1062984D01*
G01X101139Y1009353D02*
X91776Y1062434D01*
G01X126170Y976044D02*
X102464Y1009902D01*
G01X124845Y975495D02*
X101139Y1009353D01*
G01X91776Y1062434D02*
X85293Y1071694D01*
G01X93101Y1062984D02*
X86298Y1072700D01*
G01X101139Y1009353D02*
X91776Y1062434D01*
G01X102464Y1009902D02*
X93101Y1062984D01*
G01X124845Y975495D02*
X101139Y1009353D01*
G01X126170Y976044D02*
X102464Y1009902D01*
G01X105243Y1066158D02*
X70559Y1115690D01*
G01X103918Y1065609D02*
X69553Y1114684D01*
G01X115858Y1005914D02*
X105243Y1066158D01*
G01X114533Y1005361D02*
X103918Y1065609D01*
G01D02*
X69553Y1114684D01*
G01X105243Y1066158D02*
X70559Y1115690D01*
G01X114533Y1005361D02*
X103918Y1065609D01*
G01X115858Y1005914D02*
X105243Y1066158D01*
G01X63754Y1006220D02*
X59879Y1000686D01*
G01X64831Y1005317D02*
X61204Y1000137D01*
G01X64132Y1006598D02*
X63754Y1006220D01*
G01X65035Y1005521D02*
X64831Y1005317D01*
G01X66378Y1008170D02*
X64132Y1006598D01*
G01X66927Y1006845D02*
X65035Y1005521D01*
G01X71555Y1009084D02*
X66378Y1008170D01*
G01X71678Y1007684D02*
X66927Y1006845D01*
G01X75307Y1009084D02*
X71555D01*
G01X75184Y1007684D02*
X71678D01*
G01X80016Y1008253D02*
X75307Y1009084D01*
G01X79467Y1006928D02*
X75184Y1007684D01*
G01X64831Y1005317D02*
X61204Y1000137D01*
G01X63754Y1006220D02*
X59879Y1000686D01*
G01X65035Y1005521D02*
X64831Y1005317D01*
G01X64132Y1006598D02*
X63754Y1006220D01*
G01X66927Y1006845D02*
X65035Y1005521D01*
G01X66378Y1008170D02*
X64132Y1006598D01*
G01X71678Y1007684D02*
X66927Y1006845D01*
G01X71555Y1009084D02*
X66378Y1008170D01*
G01X75184Y1007684D02*
X71678D01*
G01X75307Y1009084D02*
X71555D01*
G01X79467Y1006928D02*
X75184Y1007684D01*
G01X80016Y1008253D02*
X75307Y1009084D01*
G01X122043Y1128978D02*
X89117Y1152034D01*
G01X121494Y1127653D02*
X88111Y1151028D01*
G01X121494Y1127653D02*
X88111Y1151028D01*
G01X122043Y1128978D02*
X89117Y1152034D01*
G01X97808Y1132302D02*
X41175Y1213187D01*
G01X96802Y1131296D02*
X40169Y1212181D01*
G01X132217Y1108206D02*
X97808Y1132302D01*
G01X131668Y1106881D02*
X96802Y1131296D01*
G01D02*
X40169Y1212181D01*
G01X97808Y1132302D02*
X41175Y1213187D01*
G01X131668Y1106881D02*
X96802Y1131296D01*
G01X132217Y1108206D02*
X97808Y1132302D01*
G01X59585Y1160198D02*
X113821Y1082710D01*
G01X58579Y1159192D02*
X112496Y1082161D01*
G01X58579Y1159192D02*
X112496Y1082161D01*
G01X59585Y1160198D02*
X113821Y1082710D01*
G01X110433Y1079909D02*
X57312Y1155763D01*
G01X109108Y1079359D02*
X56323Y1154734D01*
G01X122955Y1008920D02*
X110433Y1079908D01*
G01X121630Y1008371D02*
X109107Y1079359D01*
G01X109108D02*
X56323Y1154734D01*
G01X110433Y1079909D02*
X57312Y1155763D01*
G01X121630Y1008371D02*
X109107Y1079359D01*
G01X122955Y1008920D02*
X110433Y1079908D01*
G01X114159Y1100300D02*
X44829Y1199315D01*
G01X113153Y1099294D02*
X43823Y1198309D01*
G01X113153Y1099294D02*
X43823Y1198309D01*
G01X114159Y1100300D02*
X44829Y1199315D01*
G01X58576Y1144369D02*
X107584Y1074378D01*
G01X57570Y1143363D02*
X106259Y1073829D01*
G01X57570Y1143363D02*
X106259Y1073829D01*
G01X58576Y1144369D02*
X107584Y1074378D01*
G01X117837Y1086534D02*
X54406Y1177129D01*
G01X116512Y1085985D02*
X53400Y1176123D01*
G01X116512Y1085985D02*
X53400Y1176123D01*
G01X117837Y1086534D02*
X54406Y1177129D01*
G01X81360Y1088497D02*
X96119Y1067418D01*
G01X80356Y1087489D02*
X94794Y1066868D01*
G01X42044Y1116025D02*
X81360Y1088497D01*
G01X41495Y1114699D02*
X80356Y1087489D01*
G01D02*
X94794Y1066868D01*
G01X81360Y1088497D02*
X96119Y1067418D01*
G01X41495Y1114699D02*
X80356Y1087489D01*
G01X42044Y1116025D02*
X81360Y1088497D01*
G01X86298Y1072700D02*
X42341Y1103477D01*
G01X85293Y1071694D02*
X41792Y1102151D01*
G01X85293Y1071694D02*
X41792Y1102151D01*
G01X86298Y1072700D02*
X42341Y1103477D01*
G01X69284Y1209452D02*
X65380Y1215028D01*
G01X68278Y1208446D02*
X64055Y1214479D01*
G01X83891Y1199225D02*
X69284Y1209452D01*
G01X83342Y1197900D02*
X68278Y1208446D01*
G01X90328Y1198089D02*
X83891Y1199225D01*
G01X90328Y1196667D02*
X83342Y1197900D01*
G01X153011Y1209143D02*
X90328Y1198089D01*
G01X153011Y1207721D02*
X90328Y1196667D01*
G01X68278Y1208446D02*
X64055Y1214479D01*
G01X69284Y1209452D02*
X65380Y1215028D01*
G01X83342Y1197900D02*
X68278Y1208446D01*
G01X83891Y1199225D02*
X69284Y1209452D01*
G01X90328Y1196667D02*
X83342Y1197900D01*
G01X90328Y1198089D02*
X83891Y1199225D01*
G01X153011Y1207721D02*
X90328Y1196667D01*
G01X153011Y1209143D02*
X90328Y1198089D01*
G01X66506Y1207006D02*
X61953Y1213507D01*
G01X65500Y1206000D02*
X60628Y1212958D01*
G01X82505Y1195802D02*
X66506Y1207006D01*
G01X81956Y1194477D02*
X65500Y1206000D01*
G01X91001Y1194305D02*
X82505Y1195802D01*
G01X91001Y1192883D02*
X81956Y1194477D01*
G01X153680Y1205358D02*
X91001Y1194305D01*
G01X153680Y1203936D02*
X91001Y1192883D01*
G01X48596Y1209903D02*
X43641Y1238002D01*
G01X47271Y1209354D02*
X42316Y1237453D01*
G01X89117Y1152034D02*
X48596Y1209903D01*
G01X88111Y1151028D02*
X47271Y1209354D01*
G01D02*
X42316Y1237453D01*
G01X48596Y1209903D02*
X43641Y1238002D01*
G01X88111Y1151028D02*
X47271Y1209354D01*
G01X89117Y1152034D02*
X48596Y1209903D01*
G01X65500Y1206000D02*
X60628Y1212958D01*
G01X66506Y1207006D02*
X61953Y1213507D01*
G01X81956Y1194477D02*
X65500Y1206000D01*
G01X82505Y1195802D02*
X66506Y1207006D01*
G01X91001Y1192883D02*
X81956Y1194477D01*
G01X91001Y1194305D02*
X82505Y1195802D01*
G01X153680Y1203936D02*
X91001Y1192883D01*
G01X153680Y1205358D02*
X91001Y1194305D01*
G01X63744Y1204581D02*
X58325Y1212321D01*
G01X62738Y1203575D02*
X57000Y1211772D01*
G01X81108Y1192422D02*
X63744Y1204581D01*
G01X80559Y1191097D02*
X62738Y1203575D01*
G01X91163Y1190648D02*
X81108Y1192422D01*
G01X91163Y1189226D02*
X80559Y1191097D01*
G01X153846Y1201702D02*
X91163Y1190648D01*
G01X153846Y1200280D02*
X91163Y1189226D01*
G01X62738Y1203575D02*
X57000Y1211772D01*
G01X63744Y1204581D02*
X58325Y1212321D01*
G01X80559Y1191097D02*
X62738Y1203575D01*
G01X81108Y1192422D02*
X63744Y1204581D01*
G01X91163Y1189226D02*
X80559Y1191097D01*
G01X91163Y1190648D02*
X81108Y1192422D01*
G01X153846Y1200280D02*
X91163Y1189226D01*
G01X153846Y1201702D02*
X91163Y1190648D01*
G01X91000Y1186942D02*
X153766Y1198010D01*
G01X91000Y1185520D02*
X153766Y1196588D01*
G01X79931Y1188894D02*
X91000Y1186942D01*
G01X79382Y1187569D02*
X91000Y1185520D01*
G01X60795Y1202295D02*
X79931Y1188894D01*
G01X59789Y1201289D02*
X79382Y1187569D01*
G01X54506Y1211276D02*
X60795Y1202295D01*
G01X53181Y1210727D02*
X59789Y1201289D01*
G01X47832Y1249134D02*
X54506Y1211276D01*
G01X46507Y1248585D02*
X53181Y1210727D01*
G01X91000Y1185520D02*
X153766Y1196588D01*
G01X91000Y1186942D02*
X153766Y1198010D01*
G01X79382Y1187569D02*
X91000Y1185520D01*
G01X79931Y1188894D02*
X91000Y1186942D01*
G01X59789Y1201289D02*
X79382Y1187569D01*
G01X60795Y1202295D02*
X79931Y1188894D01*
G01X53181Y1210727D02*
X59789Y1201289D01*
G01X54506Y1211276D02*
X60795Y1202295D01*
G01X46507Y1248585D02*
X53181Y1210727D01*
G01X47832Y1249134D02*
X54506Y1211276D01*
G01X49690Y1160711D02*
X41956Y1162353D01*
G01X45533Y1160162D02*
X41386Y1161042D01*
G01X49145Y1159395D02*
X45533Y1160162D01*
G01X57312Y1155763D02*
X49690Y1160711D01*
G01X56323Y1154734D02*
X49145Y1159395D01*
G01X45533Y1160162D02*
X41386Y1161042D01*
G01X49690Y1160711D02*
X41956Y1162353D01*
G01X49145Y1159395D02*
X45533Y1160162D01*
G01X49690Y1160711D02*
X41956Y1162353D01*
G01X56323Y1154734D02*
X49145Y1159395D01*
G01X57312Y1155763D02*
X49690Y1160711D01*
G01X40660Y1156909D02*
X58576Y1144369D01*
G01X40111Y1155584D02*
X57570Y1143363D01*
G01X40111Y1155584D02*
X57570Y1143363D01*
G01X40660Y1156909D02*
X58576Y1144369D01*
G01X110986Y1274231D02*
X113506Y1275994D01*
G01X107865Y1273755D02*
X112500Y1277000D01*
G01X108414Y1272430D02*
X110986Y1274231D01*
G01X107865Y1273755D02*
X112500Y1277000D01*
G01X104226Y1271691D02*
X108414Y1272430D01*
G01X104103Y1273091D02*
X107865Y1273755D01*
G01X100911Y1271691D02*
X104226D01*
G01X101089Y1273091D02*
X104103D01*
G01X107865Y1273755D02*
X112500Y1277000D01*
G01X110986Y1274231D02*
X113506Y1275994D01*
G01X108414Y1272430D02*
X110986Y1274231D01*
G01X104103Y1273091D02*
X107865Y1273755D01*
G01X104226Y1271691D02*
X108414Y1272430D01*
G01X101089Y1273091D02*
X104103D01*
G01X100911Y1271691D02*
X104226D01*
G01X54230Y1278254D02*
X47236Y1288243D01*
G01X52905Y1277705D02*
X46230Y1287237D01*
G01X65380Y1215028D02*
X54230Y1278254D01*
G01X64055Y1214479D02*
X52905Y1277705D01*
G01D02*
X46230Y1287237D01*
G01X54230Y1278254D02*
X47236Y1288243D01*
G01X64055Y1214479D02*
X52905Y1277705D01*
G01X65380Y1215028D02*
X54230Y1278254D01*
G01X51719Y1271545D02*
X45872Y1279896D01*
G01X50394Y1270996D02*
X44866Y1278890D01*
G01X61953Y1213507D02*
X51719Y1271545D01*
G01X60628Y1212958D02*
X50394Y1270996D01*
G01D02*
X44866Y1278890D01*
G01X51719Y1271545D02*
X45872Y1279896D01*
G01X60628Y1212958D02*
X50394Y1270996D01*
G01X61953Y1213507D02*
X51719Y1271545D01*
G01X50344Y1257585D02*
X41722Y1269897D01*
G01X49019Y1257036D02*
X40716Y1268891D01*
G01X58325Y1212321D02*
X50344Y1257585D01*
G01X57000Y1211772D02*
X49019Y1257036D01*
G01D02*
X40716Y1268891D01*
G01X50344Y1257585D02*
X41722Y1269897D01*
G01X57000Y1211772D02*
X49019Y1257036D01*
G01X58325Y1212321D02*
X50344Y1257585D01*
G01X41969Y1257505D02*
X47832Y1249134D01*
G01X40963Y1256499D02*
X46507Y1248585D01*
G01X40963Y1256499D02*
X46507Y1248585D01*
G01X41969Y1257505D02*
X47832Y1249134D01*
G01X72534Y1398634D02*
X42073Y1355131D01*
G01X44197Y1355722D02*
X43079Y1354125D01*
G01X110014Y1291550D02*
X113506Y1293994D01*
G01X109464Y1292875D02*
X112500Y1295000D01*
G01X109465Y1292875D02*
X109464D01*
G01X104531Y1290583D02*
X110014Y1291550D01*
G01X109465Y1292875D02*
X109464D01*
G01X104408Y1291983D02*
X109465Y1292875D01*
G01X100905Y1290583D02*
X104531D01*
G01X101095Y1291983D02*
X104408D01*
G01X44197Y1355722D02*
X43079Y1354125D01*
G01X72534Y1398634D02*
X42073Y1355131D01*
G01X72534Y1398634D02*
X42073Y1355131D01*
G01X109464Y1292875D02*
X112500Y1295000D01*
G01X110014Y1291550D02*
X113506Y1293994D01*
G01X109465Y1292875D02*
X109464D01*
G01X110014Y1291550D02*
X113506Y1293994D01*
G01X104531Y1290583D02*
X110014Y1291550D01*
G01X104408Y1291983D02*
X109465Y1292875D01*
G01X104531Y1290583D02*
X110014Y1291550D01*
G01X101095Y1291983D02*
X104408D01*
G01X100905Y1290583D02*
X104531D01*
G01X40881Y1339559D02*
X39850Y1339740D01*
G01X49265Y1348043D02*
X41282Y1342452D01*
G01X44257Y1342826D02*
X42660Y1341708D01*
G01X45288Y1342644D02*
X44257Y1342826D01*
G01X50271Y1347037D02*
X47067Y1344794D01*
G01X68217Y1375109D02*
X49265Y1348043D01*
G01X69223Y1374103D02*
X50271Y1347037D01*
G01X109331Y1310422D02*
X113006Y1312994D01*
G01X108782Y1311747D02*
X112000Y1314000D01*
G01X104525Y1309575D02*
X109331Y1310422D01*
G01X104402Y1310975D02*
X108782Y1311747D01*
G01X100999Y1309575D02*
X104525D01*
G01X101001Y1310975D02*
X104402D01*
G01X40881Y1339559D02*
X39850Y1339740D01*
G01X44257Y1342826D02*
X42660Y1341708D01*
G01X49265Y1348043D02*
X41282Y1342452D01*
G01X45288Y1342644D02*
X44257Y1342826D01*
G01X49265Y1348043D02*
X41282Y1342452D01*
G01X50271Y1347037D02*
X47067Y1344794D01*
G01X49265Y1348043D02*
X41282Y1342452D01*
G01X69223Y1374103D02*
X50271Y1347037D01*
G01X68217Y1375109D02*
X49265Y1348043D01*
G01X108782Y1311747D02*
X112000Y1314000D01*
G01X109331Y1310422D02*
X113006Y1312994D01*
G01X104402Y1310975D02*
X108782Y1311747D01*
G01X104525Y1309575D02*
X109331Y1310422D01*
G01X101001Y1310975D02*
X104402D01*
G01X100999Y1309575D02*
X104525D01*
G01X39932Y1330051D02*
X38902Y1330232D01*
G01X41529Y1331169D02*
X39932Y1330051D01*
G01X44339Y1333136D02*
X43309Y1333318D01*
G01X48791Y1336253D02*
X44339Y1333136D01*
G01X49037Y1336498D02*
G02X48791Y1336253I-818J575D01*
G01X50182Y1335692D02*
G02X49593Y1335103I-1966J1377D01*
G01X50155Y1338095D02*
X49037Y1336498D01*
G01X61971Y1352528D02*
X50185Y1335694D01*
G01X53241Y1342502D02*
X52123Y1340905D01*
G01X61971Y1352528D02*
X50185Y1335694D01*
G01X56327Y1346909D02*
X55209Y1345312D01*
G01X61971Y1352528D02*
X50185Y1335694D01*
G01X60965Y1353534D02*
X58294Y1349719D01*
G01X61971Y1352528D02*
X50185Y1335694D01*
G01X64556Y1356048D02*
X60965Y1353534D01*
G01X65103Y1354719D02*
X61972Y1352529D01*
G01X66480Y1356368D02*
X64556Y1356048D01*
G01X77007Y1356696D02*
X65103Y1354719D01*
G01X77044Y1358122D02*
X69863Y1356930D01*
G01X77007Y1356696D02*
X65103Y1354719D01*
G01X97389Y1353646D02*
X77044Y1358122D01*
G01X97493Y1352189D02*
X77007Y1356696D01*
G01X102826Y1355685D02*
X97390Y1353646D01*
G01X103802Y1354554D02*
X97493Y1352189D01*
G01X104000Y1357810D02*
X102826Y1355685D01*
G01X105400Y1357448D02*
X103802Y1354554D01*
G01X39932Y1330051D02*
X38902Y1330232D01*
G01X41529Y1331169D02*
X39932Y1330051D01*
G01X44339Y1333136D02*
X43309Y1333318D01*
G01X48791Y1336253D02*
X44339Y1333136D01*
G01X50182Y1335692D02*
G02X49593Y1335103I-1966J1377D01*
G01X49037Y1336498D02*
G02X48791Y1336253I-818J575D01*
G01X61971Y1352528D02*
X50185Y1335694D01*
G01X50155Y1338095D02*
X49037Y1336498D01*
G01X53241Y1342502D02*
X52123Y1340905D01*
G01X56327Y1346909D02*
X55209Y1345312D01*
G01X60965Y1353534D02*
X58294Y1349719D01*
G01X65103Y1354719D02*
X61972Y1352529D01*
G01X64556Y1356048D02*
X60965Y1353534D01*
G01X77007Y1356696D02*
X65103Y1354719D01*
G01X66480Y1356368D02*
X64556Y1356048D01*
G01X77044Y1358122D02*
X69863Y1356930D01*
G01X97493Y1352189D02*
X77007Y1356696D01*
G01X97389Y1353646D02*
X77044Y1358122D01*
G01X103802Y1354554D02*
X97493Y1352189D01*
G01X102826Y1355685D02*
X97390Y1353646D01*
G01X105400Y1357448D02*
X103802Y1354554D01*
G01X104000Y1357810D02*
X102826Y1355685D01*
G01X42213Y1367948D02*
X40616Y1366829D01*
G01X43187Y1367776D02*
X42213Y1367948D01*
G01X48194Y1372137D02*
X44957Y1369870D01*
G01X57417Y1387749D02*
X47188Y1373143D01*
G01X58742Y1387200D02*
X48194Y1372137D01*
G01X60648Y1406083D02*
X57417Y1387749D01*
G01X60133Y1395094D02*
X58742Y1387200D01*
G01X61053Y1400314D02*
X60715Y1398394D01*
G01X61973Y1405534D02*
X61635Y1403614D01*
G01X65192Y1412572D02*
X60648Y1406083D01*
G01X66198Y1411566D02*
X61973Y1405534D01*
G01X67924Y1414483D02*
X65192Y1412572D01*
G01X68473Y1413158D02*
X66198Y1411566D01*
G01X73954Y1415547D02*
X67924Y1414483D01*
G01X73954Y1414125D02*
X68473Y1413158D01*
G01X82931Y1413964D02*
X73954Y1415547D01*
G01X82382Y1412639D02*
X73954Y1414125D01*
G01X121597Y1386892D02*
X82931Y1413964D01*
G01X120588Y1385889D02*
X82382Y1412639D01*
G01X42213Y1367948D02*
X40616Y1366829D01*
G01X43187Y1367776D02*
X42213Y1367948D01*
G01X48194Y1372137D02*
X44957Y1369870D01*
G01X58742Y1387200D02*
X48194Y1372137D01*
G01X57417Y1387749D02*
X47188Y1373143D01*
G01X60133Y1395094D02*
X58742Y1387200D01*
G01X60648Y1406083D02*
X57417Y1387749D01*
G01X61053Y1400314D02*
X60715Y1398394D01*
G01X60648Y1406083D02*
X57417Y1387749D01*
G01X61973Y1405534D02*
X61635Y1403614D01*
G01X60648Y1406083D02*
X57417Y1387749D01*
G01X66198Y1411566D02*
X61973Y1405534D01*
G01X65192Y1412572D02*
X60648Y1406083D01*
G01X68473Y1413158D02*
X66198Y1411566D01*
G01X67924Y1414483D02*
X65192Y1412572D01*
G01X73954Y1414125D02*
X68473Y1413158D01*
G01X73954Y1415547D02*
X67924Y1414483D01*
G01X82382Y1412639D02*
X73954Y1414125D01*
G01X82931Y1413964D02*
X73954Y1415547D01*
G01X120588Y1385889D02*
X82382Y1412639D01*
G01X121597Y1386892D02*
X82931Y1413964D01*
G01X49147Y1411222D02*
X45494Y1406006D01*
G01X50472Y1410673D02*
X46500Y1405000D01*
G01X62663Y1487834D02*
X49147Y1411222D01*
G01X63988Y1487285D02*
X50472Y1410673D01*
G01D02*
X46500Y1405000D01*
G01X49147Y1411222D02*
X45494Y1406006D01*
G01X63988Y1487285D02*
X50472Y1410673D01*
G01X62663Y1487834D02*
X49147Y1411222D01*
G01X52992Y1410499D02*
X41161Y1393604D01*
G01X54317Y1409950D02*
X42167Y1392598D01*
G01X66422Y1486654D02*
X52992Y1410499D01*
G01X67747Y1486105D02*
X54317Y1409950D01*
G01D02*
X42167Y1392598D01*
G01X52992Y1410499D02*
X41161Y1393604D01*
G01X67747Y1486105D02*
X54317Y1409950D01*
G01X66422Y1486654D02*
X52992Y1410499D01*
G01X86132Y1433854D02*
X62415Y1417250D01*
G01X86681Y1432529D02*
X63421Y1416244D01*
G01X86681Y1432529D02*
X63421Y1416244D01*
G01X86132Y1433854D02*
X62415Y1417250D01*
G01X73540Y1397628D02*
X46119Y1358467D01*
G01X79727Y1403668D02*
X72534Y1398634D01*
G01X80276Y1402343D02*
X73540Y1397628D01*
G01X85750Y1404731D02*
X79727Y1403668D01*
G01X85750Y1403309D02*
X80276Y1402343D01*
G01X89969Y1403986D02*
X85750Y1404731D01*
G01X89420Y1402661D02*
X85750Y1403309D01*
G01X118427Y1384060D02*
X89969Y1403986D01*
G01X91017Y1401542D02*
X89420Y1402661D01*
G01X93827Y1399575D02*
X92796Y1399393D01*
G01X95424Y1398457D02*
X93827Y1399575D01*
G01X98234Y1396489D02*
X97203Y1396307D01*
G01X99831Y1395371D02*
X98234Y1396489D01*
G01X102641Y1393403D02*
X101610Y1393222D01*
G01X117421Y1383054D02*
X102641Y1393403D01*
G01X73540Y1397628D02*
X46119Y1358467D01*
G01X80276Y1402343D02*
X73540Y1397628D01*
G01X79727Y1403668D02*
X72534Y1398634D01*
G01X85750Y1403309D02*
X80276Y1402343D01*
G01X85750Y1404731D02*
X79727Y1403668D01*
G01X89420Y1402661D02*
X85750Y1403309D01*
G01X89969Y1403986D02*
X85750Y1404731D01*
G01X91017Y1401542D02*
X89420Y1402661D01*
G01X118427Y1384060D02*
X89969Y1403986D01*
G01X93827Y1399575D02*
X92796Y1399393D01*
G01X118427Y1384060D02*
X89969Y1403986D01*
G01X95424Y1398457D02*
X93827Y1399575D01*
G01X118427Y1384060D02*
X89969Y1403986D01*
G01X98234Y1396489D02*
X97203Y1396307D01*
G01X118427Y1384060D02*
X89969Y1403986D01*
G01X99831Y1395371D02*
X98234Y1396489D01*
G01X118427Y1384060D02*
X89969Y1403986D01*
G01X102641Y1393403D02*
X101610Y1393222D01*
G01X118427Y1384060D02*
X89969Y1403986D01*
G01X117421Y1383054D02*
X102641Y1393403D01*
G01X118427Y1384060D02*
X89969Y1403986D01*
G01X88986Y1389650D02*
X68217Y1375109D01*
G01X70820Y1375221D02*
X69223Y1374103D01*
G01X71851Y1375040D02*
X70820Y1375221D01*
G01X75227Y1378307D02*
X73630Y1377189D01*
G01X76258Y1378125D02*
X75227Y1378307D01*
G01X79635Y1381393D02*
X78037Y1380275D01*
G01X80665Y1381211D02*
X79635Y1381393D01*
G01X89535Y1388325D02*
X82444Y1383360D01*
G01X95099Y1390728D02*
X88986Y1389650D01*
G01X95099Y1389306D02*
X89535Y1388325D01*
G01X104578Y1389056D02*
X95099Y1390728D01*
G01X104029Y1387731D02*
X95099Y1389306D01*
G01X115071Y1381712D02*
X104578Y1389056D01*
G01X114065Y1380706D02*
X104029Y1387731D01*
G01X70820Y1375221D02*
X69223Y1374103D01*
G01X88986Y1389650D02*
X68217Y1375109D01*
G01X71851Y1375040D02*
X70820Y1375221D01*
G01X88986Y1389650D02*
X68217Y1375109D01*
G01X75227Y1378307D02*
X73630Y1377189D01*
G01X88986Y1389650D02*
X68217Y1375109D01*
G01X76258Y1378125D02*
X75227Y1378307D01*
G01X88986Y1389650D02*
X68217Y1375109D01*
G01X79635Y1381393D02*
X78037Y1380275D01*
G01X88986Y1389650D02*
X68217Y1375109D01*
G01X80665Y1381211D02*
X79635Y1381393D01*
G01X88986Y1389650D02*
X68217Y1375109D01*
G01X89535Y1388325D02*
X82444Y1383360D01*
G01X88986Y1389650D02*
X68217Y1375109D01*
G01X95099Y1389306D02*
X89535Y1388325D01*
G01X95099Y1390728D02*
X88986Y1389650D01*
G01X104029Y1387731D02*
X95099Y1389306D01*
G01X104578Y1389056D02*
X95099Y1390728D01*
G01X114065Y1380706D02*
X104029Y1387731D01*
G01X115071Y1381712D02*
X104578Y1389056D01*
G01X104000Y1359500D02*
Y1357810D01*
G01X105400Y1360080D02*
Y1357448D01*
G01X103300Y1360200D02*
X104000Y1359500D01*
G01X103880Y1361600D02*
X105400Y1360080D01*
G01X101231Y1360200D02*
X103300D01*
G01X100769Y1361600D02*
X103880D01*
G01X105400Y1360080D02*
Y1357448D01*
G01X104000Y1359500D02*
Y1357810D01*
G01X103880Y1361600D02*
X105400Y1360080D01*
G01X103300Y1360200D02*
X104000Y1359500D01*
G01X100769Y1361600D02*
X103880D01*
G01X101231Y1360200D02*
X103300D01*
G01X59017Y1489019D02*
X49741Y1436417D01*
G01X60342Y1488470D02*
X51066Y1435868D01*
G01X66913Y1500299D02*
X59017Y1489019D01*
G01X67919Y1499293D02*
X60342Y1488470D01*
G01X101839Y1524753D02*
X66913Y1500299D01*
G01X102388Y1523428D02*
X67919Y1499293D01*
G01X60342Y1488470D02*
X51066Y1435868D01*
G01X59017Y1489019D02*
X49741Y1436417D01*
G01X67919Y1499293D02*
X60342Y1488470D01*
G01X66913Y1500299D02*
X59017Y1489019D01*
G01X102388Y1523428D02*
X67919Y1499293D01*
G01X101839Y1524753D02*
X66913Y1500299D01*
G01X69236Y1497224D02*
X62663Y1487834D01*
G01X70242Y1496218D02*
X63988Y1487285D01*
G01X79975Y1504742D02*
X69236Y1497224D01*
G01X80524Y1503417D02*
X70242Y1496218D01*
G01D02*
X63988Y1487285D01*
G01X69236Y1497224D02*
X62663Y1487834D01*
G01X80524Y1503417D02*
X70242Y1496218D01*
G01X79975Y1504742D02*
X69236Y1497224D01*
G01X71557Y1493989D02*
X66422Y1486654D01*
G01X72563Y1492983D02*
X67747Y1486105D01*
G01X81483Y1500939D02*
X71557Y1493989D01*
G01X82032Y1499614D02*
X72563Y1492983D01*
G01X89706Y1502389D02*
X81483Y1500939D01*
G01X89706Y1500967D02*
X82032Y1499614D01*
G01X139693Y1493575D02*
X89706Y1502389D01*
G01X139570Y1492175D02*
X89706Y1500967D01*
G01X72563Y1492983D02*
X67747Y1486105D01*
G01X71557Y1493989D02*
X66422Y1486654D01*
G01X82032Y1499614D02*
X72563Y1492983D01*
G01X81483Y1500939D02*
X71557Y1493989D01*
G01X89706Y1500967D02*
X82032Y1499614D01*
G01X89706Y1502389D02*
X81483Y1500939D01*
G01X139570Y1492175D02*
X89706Y1500967D01*
G01X139693Y1493575D02*
X89706Y1502389D01*
G01X139031Y1443181D02*
X86132Y1433854D01*
G01X139154Y1441781D02*
X86681Y1432529D01*
G01X139154Y1441781D02*
X86681Y1432529D01*
G01X139031Y1443181D02*
X86132Y1433854D01*
G01X47127Y1573944D02*
X73906Y1592695D01*
G01X47676Y1572619D02*
X74455Y1591370D01*
G01X47676Y1572619D02*
X74455Y1591370D01*
G01X47127Y1573944D02*
X73906Y1592695D01*
G01X80462Y1590087D02*
X58385Y1574629D01*
G01X80462Y1590087D02*
X58385Y1574629D01*
G01X48042Y1551569D02*
X39092Y1538786D01*
G01X92668Y1584521D02*
X47036Y1552575D01*
G01X93217Y1583196D02*
X48042Y1551569D01*
G01D02*
X39092Y1538786D01*
G01X93217Y1583196D02*
X48042Y1551569D01*
G01X92668Y1584521D02*
X47036Y1552575D01*
G01X139365Y1531370D02*
X101839Y1524753D01*
G01X139488Y1529970D02*
X102388Y1523428D01*
G01X139488Y1529970D02*
X102388Y1523428D01*
G01X139365Y1531370D02*
X101839Y1524753D01*
G01X126593Y1512964D02*
X79975Y1504742D01*
G01X126593Y1511542D02*
X80524Y1503417D01*
G01X126593Y1511542D02*
X80524Y1503417D01*
G01X126593Y1512964D02*
X79975Y1504742D01*
G01X56020Y1624007D02*
G03X55811Y1624068I-383J-924D01*
G01X56556Y1625301D02*
G03X56053Y1625448I-921J-2216D01*
G01X75569Y1615901D02*
X56020Y1624007D01*
G01X76106Y1617194D02*
X56556Y1625301D01*
G01X76000Y1615775D02*
G02X75570Y1615900I354J2019D01*
G01X76242Y1617154D02*
G02X76106Y1617194I114J639D01*
G01X93352Y1612716D02*
X76000Y1615775D01*
G01X93596Y1614095D02*
X76242Y1617154D01*
G01X94186Y1612716D02*
G02X93352I-417J2364D01*
G01X93943Y1614095D02*
G02X93596I-173J985D01*
G01X156636Y1623729D02*
X94186Y1612716D01*
G01X156393Y1625108D02*
X93943Y1614095D01*
G01X56556Y1625301D02*
G03X56053Y1625448I-921J-2216D01*
G01X56020Y1624007D02*
G03X55811Y1624068I-383J-924D01*
G01X76106Y1617194D02*
X56556Y1625301D01*
G01X75569Y1615901D02*
X56020Y1624007D01*
G01X76242Y1617154D02*
G02X76106Y1617194I114J639D01*
G01X76000Y1615775D02*
G02X75570Y1615900I354J2019D01*
G01X93596Y1614095D02*
X76242Y1617154D01*
G01X93352Y1612716D02*
X76000Y1615775D01*
G01X93943Y1614095D02*
G02X93596I-173J985D01*
G01X94186Y1612716D02*
G02X93352I-417J2364D01*
G01X156393Y1625108D02*
X93943Y1614095D01*
G01X156636Y1623729D02*
X94186Y1612716D01*
G01X41125Y1616384D02*
X41124D01*
G01X41368Y1617763D02*
X88276Y1609492D01*
G01X88254Y1608074D02*
X41125Y1616384D01*
G01X41368Y1617763D02*
X88276Y1609492D01*
G01X92955Y1608756D02*
X88254Y1608074D01*
G01X88276Y1609492D02*
X92733Y1610139D01*
G01X158590Y1620327D02*
X92955Y1608756D01*
G01X92743Y1610141D02*
X158347Y1621706D01*
G01X92733Y1610139D02*
X92743Y1610141D01*
G01D02*
X158347Y1621706D01*
G01X158590Y1620327D02*
X92955Y1608756D01*
G01X92733Y1610139D02*
X92743Y1610141D01*
G01X158590Y1620327D02*
X92955Y1608756D01*
G01X88276Y1609492D02*
X92733Y1610139D01*
G01X92955Y1608756D02*
X88254Y1608074D01*
G01X41368Y1617763D02*
X88276Y1609492D01*
G01X41125Y1616384D02*
X41124D01*
G01X88254Y1608074D02*
X41125Y1616384D01*
G01X60222Y1598132D02*
X162394Y1616149D01*
G01X60222Y1599554D02*
X162151Y1617528D01*
G01X60222Y1599554D02*
X162151Y1617528D01*
G01X60222Y1598132D02*
X162394Y1616149D01*
G01X58712Y1594188D02*
X51897Y1595390D01*
G01Y1596812D02*
X58712Y1595610D01*
G01X164010Y1612760D02*
X58712Y1594188D01*
G01Y1595610D02*
X163766Y1614139D01*
G01X58712Y1595610D02*
X163766Y1614139D01*
G01X164010Y1612760D02*
X58712Y1594188D01*
G01X51897Y1596812D02*
X58712Y1595610D01*
G01Y1594188D02*
X51897Y1595390D01*
G01X73906Y1592695D02*
X176414Y1610773D01*
G01X74455Y1591370D02*
X176657Y1609394D01*
G01X74455Y1591370D02*
X176657Y1609394D01*
G01X73906Y1592695D02*
X176414Y1610773D01*
G01X176402Y1607006D02*
X80462Y1590087D01*
G01X176645Y1605626D02*
X81011Y1588762D01*
G01X176645Y1605626D02*
X81011Y1588762D01*
G01X176402Y1607006D02*
X80462Y1590087D01*
G01X177293Y1603216D02*
X90773Y1587958D01*
G01X177536Y1601837D02*
X91322Y1586633D01*
G01X177536Y1601837D02*
X91322Y1586633D01*
G01X177293Y1603216D02*
X90773Y1587958D01*
G01X176935Y1599379D02*
X92668Y1584521D01*
G01X177178Y1597999D02*
X93217Y1583196D01*
G01X177178Y1597999D02*
X93217Y1583196D01*
G01X176935Y1599379D02*
X92668Y1584521D01*
G01X39973Y1699474D02*
X39095Y1698220D01*
G01X41298Y1698923D02*
X40101Y1697214D01*
G01X59219Y1808615D02*
X39973Y1699474D01*
G01X60544Y1808066D02*
X41298Y1698923D01*
G01D02*
X40101Y1697214D01*
G01X39973Y1699474D02*
X39095Y1698220D01*
G01X60544Y1808066D02*
X41298Y1698923D01*
G01X59219Y1808615D02*
X39973Y1699474D01*
G01X42151Y1690900D02*
X58760Y1785082D01*
G01X43501Y1690492D02*
X60139Y1784839D01*
G01X39035Y1686448D02*
X42151Y1690900D01*
G01X40041Y1685442D02*
X43393Y1690233D01*
G01X43501Y1690492D02*
X60139Y1784839D01*
G01X42151Y1690900D02*
X58760Y1785082D01*
G01X40041Y1685442D02*
X43393Y1690233D01*
G01X39035Y1686448D02*
X42151Y1690900D01*
G01X60019Y1769588D02*
X44438Y1681254D01*
G01X61398Y1769346D02*
X45738Y1680563D01*
G01X61398Y1769346D02*
X45738Y1680563D01*
G01X60019Y1769588D02*
X44438Y1681254D01*
G01X107215Y1677922D02*
X127180Y1665376D01*
G01X106469Y1676736D02*
X117458Y1669830D01*
G01X106831Y1678118D02*
G02X107215Y1677922I-895J-2227D01*
G01X106309Y1676818D02*
G02X106469Y1676737I-370J-929D01*
G01X106434Y1678277D02*
X106831Y1678118D01*
G01X105914Y1676976D02*
X106309Y1676818D01*
G01X106021Y1678400D02*
G02X106434Y1678277I-476J-2352D01*
G01X105743Y1677027D02*
G02X105914Y1676976I-199J-979D01*
G01X103164Y1678981D02*
X106021Y1678400D01*
G01X102885Y1677609D02*
X105743Y1677027D01*
G01X102686Y1679029D02*
G02X103164Y1678981I0J-2400D01*
G01X102686Y1677629D02*
G02X102885Y1677609I0J-1000D01*
G01X100663Y1679029D02*
X102686D01*
G01X101337Y1677629D02*
X102686D01*
G01X107215Y1677922D02*
X127180Y1665376D01*
G01X107215Y1677922D02*
X127180Y1665376D01*
G01X107215Y1677922D02*
X127180Y1665376D01*
G01X106469Y1676736D02*
X117458Y1669830D01*
G01X107215Y1677922D02*
X127180Y1665376D01*
G01X106309Y1676818D02*
G02X106469Y1676737I-370J-929D01*
G01X106831Y1678118D02*
G02X107215Y1677922I-895J-2227D01*
G01X105914Y1676976D02*
X106309Y1676818D01*
G01X106434Y1678277D02*
X106831Y1678118D01*
G01X105743Y1677027D02*
G02X105914Y1676976I-199J-979D01*
G01X106021Y1678400D02*
G02X106434Y1678277I-476J-2352D01*
G01X102885Y1677609D02*
X105743Y1677027D01*
G01X103164Y1678981D02*
X106021Y1678400D01*
G01X102686Y1677629D02*
G02X102885Y1677609I0J-1000D01*
G01X102686Y1679029D02*
G02X103164Y1678981I0J-2400D01*
G01X101337Y1677629D02*
X102686D01*
G01X100663Y1679029D02*
X102686D01*
G01X109792Y1696756D02*
X158985Y1662311D01*
G01X111252Y1694024D02*
X109243Y1695431D01*
G01X105064Y1697589D02*
X109792Y1696756D01*
G01X109243Y1695431D02*
X104941Y1696189D01*
G01X101001Y1697589D02*
X105064D01*
G01X104941Y1696189D02*
X100999D01*
G01X104941D02*
X100999D01*
G01X101001Y1697589D02*
X105064D01*
G01X109243Y1695431D02*
X104941Y1696189D01*
G01X105064Y1697589D02*
X109792Y1696756D01*
G01X111252Y1694024D02*
X109243Y1695431D01*
G01X109792Y1696756D02*
X158985Y1662311D01*
G01X109792Y1696756D02*
X158985Y1662311D01*
G01X109792Y1696756D02*
X158985Y1662311D01*
G01X109792Y1696756D02*
X158985Y1662311D01*
G01X109792Y1696756D02*
X158985Y1662311D01*
G01X109792Y1696756D02*
X158985Y1662311D01*
G01X109792Y1696756D02*
X158985Y1662311D01*
G01X109792Y1696756D02*
X158985Y1662311D01*
G01X109792Y1696756D02*
X158985Y1662311D01*
G01X109792Y1696756D02*
X158985Y1662311D01*
G01X109792Y1696756D02*
X158985Y1662311D01*
G01X109792Y1696756D02*
X158985Y1662311D01*
G01X109792Y1696756D02*
X158985Y1662311D01*
G01X109792Y1696756D02*
X158985Y1662311D01*
G01X109792Y1696756D02*
X158985Y1662311D01*
G01X109792Y1696756D02*
X158985Y1662311D01*
G01X109792Y1696756D02*
X158985Y1662311D01*
G01X104525Y1716487D02*
X101001D01*
G01X104402Y1715087D02*
X100999D01*
G01X110550Y1715425D02*
X104525Y1716487D01*
G01X110001Y1714100D02*
X104402Y1715087D01*
G01X144862Y1691400D02*
X110550Y1715425D01*
G01X111598Y1712982D02*
X110001Y1714100D01*
G01X104402Y1715087D02*
X100999D01*
G01X104525Y1716487D02*
X101001D01*
G01X110001Y1714100D02*
X104402Y1715087D01*
G01X110550Y1715425D02*
X104525Y1716487D01*
G01X111598Y1712982D02*
X110001Y1714100D01*
G01X144862Y1691400D02*
X110550Y1715425D01*
G01X144862Y1691400D02*
X110550Y1715425D01*
G01X144862Y1691400D02*
X110550Y1715425D01*
G01X144862Y1691400D02*
X110550Y1715425D01*
G01X144862Y1691400D02*
X110550Y1715425D01*
G01X144862Y1691400D02*
X110550Y1715425D01*
G01X144862Y1691400D02*
X110550Y1715425D01*
G01X144862Y1691400D02*
X110550Y1715425D01*
G01X144862Y1691400D02*
X110550Y1715425D01*
G01X144862Y1691400D02*
X110550Y1715425D01*
G01X144862Y1691400D02*
X110550Y1715425D01*
G01X144862Y1691400D02*
X110550Y1715425D01*
G01X144862Y1691400D02*
X110550Y1715425D01*
G01X63943Y1768912D02*
X46087Y1667637D01*
G01X65322Y1768669D02*
X47412Y1667088D01*
G01X65322Y1768669D02*
X47412Y1667088D01*
G01X63943Y1768912D02*
X46087Y1667637D01*
G01X60037Y1855198D02*
X38894Y1735322D01*
G01X60037Y1855198D02*
X38894Y1735322D01*
G01X59159Y1786043D02*
X70993Y1802945D01*
G01X60306Y1785239D02*
X72062Y1802030D01*
G01X58760Y1785082D02*
G02X59158Y1786042I2363J-417D01*
G01X60140Y1784839D02*
G02X60306Y1785240I985J-173D01*
G01Y1785239D02*
X72062Y1802030D01*
G01X59159Y1786043D02*
X70993Y1802945D01*
G01X60140Y1784839D02*
G02X60306Y1785240I985J-173D01*
G01X58760Y1785082D02*
G02X59158Y1786042I2363J-417D01*
G01X60183Y1770152D02*
G03X60019Y1769588I2475J-1026D01*
G01X61476Y1769615D02*
G03X61398Y1769346I1182J-489D01*
G01X61611Y1769860D02*
G03X61476Y1769615I1057J-742D01*
G01X60464Y1770664D02*
G03X60183Y1770152I2205J-1543D01*
G01X61476Y1769615D02*
G03X61398Y1769346I1182J-489D01*
G01X61611Y1769860D02*
G03X61476Y1769615I1057J-742D01*
G01X66534Y1779335D02*
X60464Y1770664D01*
G01X67681Y1778531D02*
X61611Y1769860D01*
G01X66916Y1779788D02*
G03X66534Y1779335I2390J-2403D01*
G01X67904Y1778796D02*
G03X67681Y1778531I1404J-1408D01*
G01X68169Y1779018D02*
G03X67904Y1778796I1152J-1644D01*
G01X67366Y1780165D02*
G03X66916Y1779788I1955J-2791D01*
G01X67904Y1778796D02*
G03X67681Y1778531I1404J-1408D01*
G01X68169Y1779018D02*
G03X67904Y1778796I1152J-1644D01*
G01X75242Y1785680D02*
X67366Y1780165D01*
G01X76045Y1784533D02*
X68169Y1779018D01*
G01X75487Y1785925D02*
G02X75242Y1785680I-819J574D01*
G01X76634Y1785122D02*
G02X76045Y1784533I-1966J1377D01*
G01X79244Y1791290D02*
X75487Y1785925D01*
G01X80391Y1790487D02*
X76634Y1785122D01*
G01X80199Y1792247D02*
G03X79244Y1791290I2242J-3192D01*
G01X81003Y1791100D02*
G03X80391Y1790487I1437J-2046D01*
G01X82080Y1793565D02*
X80199Y1792247D01*
G01X82884Y1792418D02*
X81003Y1791100D01*
G01X82824Y1793974D02*
G03X82080Y1793565I1496J-3602D01*
G01X83361Y1792680D02*
G03X82884Y1792418I958J-2309D01*
G01X83853Y1792884D02*
X83361Y1792680D01*
G01X83853Y1792884D02*
X83361Y1792680D01*
G01X84374Y1793037D02*
G03X83853Y1792884I440J-2461D01*
G01X91457Y1794296D02*
X84374Y1793037D01*
G01X106240Y1793265D02*
X92573Y1795675D01*
G01X105997Y1791886D02*
X92329Y1794296D01*
G01X107800Y1792619D02*
G03X106240Y1793265I-2237J-3195D01*
G01X106997Y1791472D02*
G03X105997Y1791886I-1434J-2048D01*
G01X118894Y1784852D02*
X107800Y1792619D01*
G01X118091Y1783705D02*
X106997Y1791472D01*
G01X61476Y1769615D02*
G03X61398Y1769346I1182J-489D01*
G01X60183Y1770152D02*
G03X60019Y1769588I2475J-1026D01*
G01X60464Y1770664D02*
G03X60183Y1770152I2205J-1543D01*
G01X61611Y1769860D02*
G03X61476Y1769615I1057J-742D01*
G01X60183Y1770152D02*
G03X60019Y1769588I2475J-1026D01*
G01X60464Y1770664D02*
G03X60183Y1770152I2205J-1543D01*
G01X67681Y1778531D02*
X61611Y1769860D01*
G01X66534Y1779335D02*
X60464Y1770664D01*
G01X67904Y1778796D02*
G03X67681Y1778531I1404J-1408D01*
G01X66916Y1779788D02*
G03X66534Y1779335I2390J-2403D01*
G01X67366Y1780165D02*
G03X66916Y1779788I1955J-2791D01*
G01X68169Y1779018D02*
G03X67904Y1778796I1152J-1644D01*
G01X66916Y1779788D02*
G03X66534Y1779335I2390J-2403D01*
G01X67366Y1780165D02*
G03X66916Y1779788I1955J-2791D01*
G01X76045Y1784533D02*
X68169Y1779018D01*
G01X75242Y1785680D02*
X67366Y1780165D01*
G01X76634Y1785122D02*
G02X76045Y1784533I-1966J1377D01*
G01X75487Y1785925D02*
G02X75242Y1785680I-819J574D01*
G01X80391Y1790487D02*
X76634Y1785122D01*
G01X79244Y1791290D02*
X75487Y1785925D01*
G01X81003Y1791100D02*
G03X80391Y1790487I1437J-2046D01*
G01X80199Y1792247D02*
G03X79244Y1791290I2242J-3192D01*
G01X82884Y1792418D02*
X81003Y1791100D01*
G01X82080Y1793565D02*
X80199Y1792247D01*
G01X83361Y1792680D02*
G03X82884Y1792418I958J-2309D01*
G01X82824Y1793974D02*
G03X82080Y1793565I1496J-3602D01*
G01X83853Y1792884D02*
X83361Y1792680D01*
G01X84374Y1793037D02*
G03X83853Y1792884I440J-2461D01*
G01X91457Y1794296D02*
X84374Y1793037D01*
G01X105997Y1791886D02*
X92329Y1794296D01*
G01X106240Y1793265D02*
X92573Y1795675D01*
G01X106997Y1791472D02*
G03X105997Y1791886I-1434J-2048D01*
G01X107800Y1792619D02*
G03X106240Y1793265I-2237J-3195D01*
G01X118091Y1783705D02*
X106997Y1791472D01*
G01X118894Y1784852D02*
X107800Y1792619D01*
G01X56898Y1816572D02*
X40872Y1725674D01*
G01X55573Y1817121D02*
X39547Y1726223D01*
G01X55573Y1817121D02*
X39547Y1726223D01*
G01X56898Y1816572D02*
X40872Y1725674D01*
G01X113751Y1757356D02*
X110446Y1762075D01*
G01X111156Y1763399D02*
G02X111593Y1762878I-2758J-2757D01*
G01X110446Y1762075D02*
G03X110166Y1762409I-2048J-1433D01*
G01X110853Y1763702D02*
X111156Y1763399D01*
G01X110166Y1762409D02*
X109862Y1762713D01*
G01X110332Y1764141D02*
G02X110853Y1763702I-2243J-3191D01*
G01X109862Y1762713D02*
G03X109528Y1762994I-1770J-1765D01*
G01X107580Y1766067D02*
X110332Y1764141D01*
G01X109528Y1762994D02*
X106777Y1764920D01*
G01X106022Y1766712D02*
G02X107580Y1766067I-678J-3841D01*
G01X106777Y1764920D02*
G03X105778Y1765333I-1432J-2049D01*
G01X105362Y1766829D02*
X106022Y1766712D01*
G01X105778Y1765333D02*
X105118Y1765450D01*
G01X104761Y1766881D02*
G02X105362Y1766829I4J-3452D01*
G01X105118Y1765450D02*
G03X104761Y1765481I-355J-2021D01*
G01X101000Y1766881D02*
X104761D01*
G01Y1765481D02*
X101000D01*
G01X104761D02*
X101000D01*
G01Y1766881D02*
X104761D01*
G01X105118Y1765450D02*
G03X104761Y1765481I-355J-2021D01*
G01Y1766881D02*
G02X105362Y1766829I4J-3452D01*
G01X105778Y1765333D02*
X105118Y1765450D01*
G01X105362Y1766829D02*
X106022Y1766712D01*
G01X106777Y1764920D02*
G03X105778Y1765333I-1432J-2049D01*
G01X106022Y1766712D02*
G02X107580Y1766067I-678J-3841D01*
G01X109528Y1762994D02*
X106777Y1764920D01*
G01X107580Y1766067D02*
X110332Y1764141D01*
G01X109862Y1762713D02*
G03X109528Y1762994I-1770J-1765D01*
G01X110332Y1764141D02*
G02X110853Y1763702I-2243J-3191D01*
G01X110166Y1762409D02*
X109862Y1762713D01*
G01X110853Y1763702D02*
X111156Y1763399D01*
G01X110446Y1762075D02*
G03X110166Y1762409I-2048J-1433D01*
G01X111156Y1763399D02*
G02X111593Y1762878I-2758J-2757D01*
G01X113751Y1757356D02*
X110446Y1762075D01*
G01X64283Y1769732D02*
G03X63943Y1768912I1679J-1177D01*
G01X65430Y1768929D02*
G03X65322Y1768669I532J-373D01*
G01X69018Y1776496D02*
X64283Y1769732D01*
G01X70165Y1775692D02*
X65430Y1768929D01*
G01X69608Y1777085D02*
G03X69018Y1776496I1375J-1967D01*
G01X70411Y1775938D02*
G03X70165Y1775692I573J-819D01*
G01X78516Y1783324D02*
X69608Y1777085D01*
G01X79522Y1782318D02*
X70411Y1775938D01*
G01X82287Y1788709D02*
X78516Y1783324D01*
G01X83434Y1787906D02*
X79522Y1782318D01*
G01X82791Y1789213D02*
G03X82287Y1788709I1176J-1680D01*
G01X83594Y1788066D02*
G03X83434Y1787906I373J-533D01*
G01X84493Y1790404D02*
X82791Y1789213D01*
G01X85295Y1789256D02*
X83594Y1788066D01*
G01X85313Y1790742D02*
G03X84493Y1790404I353J-2019D01*
G01X85555Y1789363D02*
G03X85295Y1789256I111J-640D01*
G01X90809Y1791714D02*
X85313Y1790742D01*
G01X91053Y1790335D02*
X85555Y1789363D01*
G01X91645Y1791714D02*
G03X90809I-418J-2363D01*
G01X91405Y1790334D02*
G03X91057I-174J-984D01*
G01X105239Y1789318D02*
X91648Y1791713D01*
G01X104995Y1787939D02*
X91405Y1790334D01*
G01X106199Y1788920D02*
G03X105239Y1789318I-1377J-1965D01*
G01X105395Y1787773D02*
G03X104995Y1787939I-574J-819D01*
G01X116983Y1781370D02*
X106199Y1788920D01*
G01X116178Y1780224D02*
X105395Y1787773D01*
G01X65430Y1768929D02*
G03X65322Y1768669I532J-373D01*
G01X64283Y1769732D02*
G03X63943Y1768912I1679J-1177D01*
G01X70165Y1775692D02*
X65430Y1768929D01*
G01X69018Y1776496D02*
X64283Y1769732D01*
G01X70411Y1775938D02*
G03X70165Y1775692I573J-819D01*
G01X69608Y1777085D02*
G03X69018Y1776496I1375J-1967D01*
G01X79522Y1782318D02*
X70411Y1775938D01*
G01X78516Y1783324D02*
X69608Y1777085D01*
G01X83434Y1787906D02*
X79522Y1782318D01*
G01X82287Y1788709D02*
X78516Y1783324D01*
G01X83594Y1788066D02*
G03X83434Y1787906I373J-533D01*
G01X82791Y1789213D02*
G03X82287Y1788709I1176J-1680D01*
G01X85295Y1789256D02*
X83594Y1788066D01*
G01X84493Y1790404D02*
X82791Y1789213D01*
G01X85555Y1789363D02*
G03X85295Y1789256I111J-640D01*
G01X85313Y1790742D02*
G03X84493Y1790404I353J-2019D01*
G01X91053Y1790335D02*
X85555Y1789363D01*
G01X90809Y1791714D02*
X85313Y1790742D01*
G01X91405Y1790334D02*
G03X91057I-174J-984D01*
G01X91645Y1791714D02*
G03X90809I-418J-2363D01*
G01X104995Y1787939D02*
X91405Y1790334D01*
G01X105239Y1789318D02*
X91648Y1791713D01*
G01X105395Y1787773D02*
G03X104995Y1787939I-574J-819D01*
G01X106199Y1788920D02*
G03X105239Y1789318I-1377J-1965D01*
G01X116178Y1780224D02*
X105395Y1787773D01*
G01X116983Y1781370D02*
X106199Y1788920D01*
G01X95989Y1919545D02*
X53205Y1858439D01*
G01X94983Y1920551D02*
X51880Y1858988D01*
G01X94983Y1920551D02*
X51880Y1858988D01*
G01X95989Y1919545D02*
X53205Y1858439D01*
G01X83342Y1894986D02*
X56642Y1856855D01*
G01X82336Y1895992D02*
X55317Y1857404D01*
G01X82336Y1895992D02*
X55317Y1857404D01*
G01X83342Y1894986D02*
X56642Y1856855D01*
G01X72349Y1872780D02*
X60037Y1855198D01*
G01X65045Y1864792D02*
X58712Y1855747D01*
G01X71343Y1873786D02*
X65045Y1864792D01*
G01D02*
X58712Y1855747D01*
G01X72349Y1872780D02*
X60037Y1855198D01*
G01X71343Y1873786D02*
X65045Y1864792D01*
G01X72349Y1872780D02*
X60037Y1855198D01*
G01X66494Y1819006D02*
X59219Y1808615D01*
G01X67500Y1818000D02*
X60544Y1808066D01*
G01X70676Y1821933D02*
X66494Y1819006D01*
G01X71225Y1820607D02*
X67500Y1818000D01*
G01X80858Y1823729D02*
X70676Y1821933D01*
G01X80858Y1822307D02*
X71225Y1820607D01*
G01X93874Y1821433D02*
X80858Y1823729D01*
G01X93555Y1820067D02*
X80858Y1822307D01*
G01X94437Y1821269D02*
X93874Y1821433D01*
G01X93555Y1820067D02*
X80858Y1822307D01*
G01X93898Y1819967D02*
X93555Y1820067D01*
G01X93897Y1819967D02*
X93898D01*
G01X94943Y1820991D02*
X94574Y1821194D01*
G01X94203Y1819800D02*
X94052Y1819882D01*
G01X110753Y1809922D02*
X94943Y1820991D01*
G01X109747Y1808916D02*
X94202Y1819799D01*
G01X145419Y1760428D02*
X110753Y1809922D01*
G01X144271Y1759624D02*
X109747Y1808916D01*
G01X67500Y1818000D02*
X60544Y1808066D01*
G01X66494Y1819006D02*
X59219Y1808615D01*
G01X71225Y1820607D02*
X67500Y1818000D01*
G01X70676Y1821933D02*
X66494Y1819006D01*
G01X80858Y1822307D02*
X71225Y1820607D01*
G01X80858Y1823729D02*
X70676Y1821933D01*
G01X93555Y1820067D02*
X80858Y1822307D01*
G01X93874Y1821433D02*
X80858Y1823729D01*
G01X94437Y1821269D02*
X93874Y1821433D01*
G01X93898Y1819967D02*
X93555Y1820067D01*
G01X94437Y1821269D02*
X93874Y1821433D01*
G01X93897Y1819967D02*
X93898D01*
G01X94437Y1821269D02*
X93874Y1821433D01*
G01X94203Y1819800D02*
X94052Y1819882D01*
G01X94943Y1820991D02*
X94574Y1821194D01*
G01X109747Y1808916D02*
X94202Y1819799D01*
G01X110753Y1809922D02*
X94943Y1820991D01*
G01X144271Y1759624D02*
X109747Y1808916D01*
G01X145419Y1760428D02*
X110753Y1809922D01*
G01X94853Y1808505D02*
X118835Y1791715D01*
G01X94050Y1807357D02*
X117936Y1790634D01*
G01X93922Y1808897D02*
G02X94853Y1808505I-445J-2358D01*
G01X93662Y1807520D02*
G02X94050Y1807357I-184J-982D01*
G01X87085Y1810188D02*
X93922Y1808897D01*
G01X86825Y1808812D02*
X93662Y1807520D01*
G01X86222Y1810193D02*
G02X87085Y1810188I418J-2363D01*
G01X86465Y1808814D02*
G02X86825Y1808812I175J-985D01*
G01X80014Y1809097D02*
X86222Y1810193D01*
G01X80257Y1807718D02*
X86465Y1808814D01*
G01X79054Y1808699D02*
G02X80014Y1809097I1377J-1965D01*
G01X79857Y1807552D02*
G02X80257Y1807718I574J-819D01*
G01X71492Y1803404D02*
X79054Y1808699D01*
G01X76077Y1804905D02*
X79857Y1807552D01*
G01X72295Y1802257D02*
X76077Y1804905D01*
G01X71491Y1803404D02*
X71492D01*
G01X72295Y1802257D02*
X76077Y1804905D01*
G01X71399Y1803339D02*
X71491Y1803404D01*
G01X72295Y1802257D02*
X76077Y1804905D01*
G01X70993Y1802945D02*
X71399Y1803339D01*
G01X72062Y1802030D02*
X72295Y1802257D01*
G01X94050Y1807357D02*
X117936Y1790634D01*
G01X94853Y1808505D02*
X118835Y1791715D01*
G01X93662Y1807520D02*
G02X94050Y1807357I-184J-982D01*
G01X93922Y1808897D02*
G02X94853Y1808505I-445J-2358D01*
G01X86825Y1808812D02*
X93662Y1807520D01*
G01X87085Y1810188D02*
X93922Y1808897D01*
G01X86465Y1808814D02*
G02X86825Y1808812I175J-985D01*
G01X86222Y1810193D02*
G02X87085Y1810188I418J-2363D01*
G01X80257Y1807718D02*
X86465Y1808814D01*
G01X80014Y1809097D02*
X86222Y1810193D01*
G01X79857Y1807552D02*
G02X80257Y1807718I574J-819D01*
G01X79054Y1808699D02*
G02X80014Y1809097I1377J-1965D01*
G01X76077Y1804905D02*
X79857Y1807552D01*
G01X71492Y1803404D02*
X79054Y1808699D01*
G01X72295Y1802257D02*
X76077Y1804905D01*
G01X71492Y1803404D02*
X79054Y1808699D01*
G01X71491Y1803404D02*
X71492D01*
G01X71399Y1803339D02*
X71491Y1803404D01*
G01X72062Y1802030D02*
X72295Y1802257D01*
G01X70993Y1802945D02*
X71399Y1803339D01*
G01X83070Y1794075D02*
X82824Y1793974D01*
G01X83314Y1794177D02*
X83070Y1794075D01*
G01X84128Y1794416D02*
G03X83314Y1794177I685J-3840D01*
G01X91212Y1795675D02*
X84128Y1794416D01*
G01X92573Y1795675D02*
G03X91212I-681J-3841D01*
G01X92329Y1794296D02*
G03X91457I-436J-2462D01*
G01X83070Y1794075D02*
X82824Y1793974D01*
G01X83314Y1794177D02*
X83070Y1794075D01*
G01X84128Y1794416D02*
G03X83314Y1794177I685J-3840D01*
G01X91212Y1795675D02*
X84128Y1794416D01*
G01X92329Y1794296D02*
G03X91457I-436J-2462D01*
G01X92573Y1795675D02*
G03X91212I-681J-3841D01*
G01X63953Y1826645D02*
X56898Y1816572D01*
G01X62805Y1827448D02*
X55573Y1817121D01*
G01X64198Y1826890D02*
G03X63953Y1826645I574J-819D01*
G01X63395Y1828038D02*
G03X62805Y1827448I1376J-1966D01*
G01X77736Y1836369D02*
X64198Y1826890D01*
G01X76933Y1837516D02*
X63395Y1828038D01*
G01X78136Y1836534D02*
G03X77736Y1836369I172J-985D01*
G01X77893Y1837913D02*
G03X76933Y1837516I415J-2364D01*
G01X139154Y1847293D02*
X78136Y1836534D01*
G01X139031Y1848693D02*
X77893Y1837913D01*
G01X62805Y1827448D02*
X55573Y1817121D01*
G01X63953Y1826645D02*
X56898Y1816572D01*
G01X63395Y1828038D02*
G03X62805Y1827448I1376J-1966D01*
G01X64198Y1826890D02*
G03X63953Y1826645I574J-819D01*
G01X76933Y1837516D02*
X63395Y1828038D01*
G01X77736Y1836369D02*
X64198Y1826890D01*
G01X77893Y1837913D02*
G03X76933Y1837516I415J-2364D01*
G01X78136Y1836534D02*
G03X77736Y1836369I172J-985D01*
G01X139031Y1848693D02*
X77893Y1837913D01*
G01X139154Y1847293D02*
X78136Y1836534D01*
G01X111769Y1930594D02*
X95989Y1919545D01*
G01X111220Y1931919D02*
X94983Y1920551D01*
G01X139365Y1936882D02*
X111220Y1931919D01*
G01D02*
X94983Y1920551D01*
G01X111769Y1930594D02*
X95989Y1919545D01*
G01X139365Y1936882D02*
X111220Y1931919D01*
G01X105786Y1910701D02*
X83342Y1894986D01*
G01X105237Y1912026D02*
X82336Y1895992D01*
G01X139154Y1916585D02*
X105786Y1910701D01*
G01X139031Y1917985D02*
X105237Y1912026D01*
G01D02*
X82336Y1895992D01*
G01X105786Y1910701D02*
X83342Y1894986D01*
G01X139031Y1917985D02*
X105237Y1912026D01*
G01X139154Y1916585D02*
X105786Y1910701D01*
G01X97223Y1890199D02*
X72349Y1872780D01*
G01X96674Y1891524D02*
X71343Y1873786D01*
G01X139693Y1897687D02*
X97223Y1890199D01*
G01X139570Y1899087D02*
X96674Y1891524D01*
G01D02*
X71343Y1873786D01*
G01X97223Y1890199D02*
X72349Y1872780D01*
G01X139570Y1899087D02*
X96674Y1891524D01*
G01X139693Y1897687D02*
X97223Y1890199D01*
G01X140492Y118490D02*
X114589Y265393D01*
G01X139070Y118489D02*
X113264Y264844D01*
G01X134631Y85253D02*
X140492Y118490D01*
G01X135607Y98857D02*
X139070Y118489D01*
G01X134573Y92995D02*
X134948Y95113D01*
G01X133306Y85802D02*
X133914Y89251D01*
G01X117849Y61285D02*
X134631Y85253D01*
G01X132069Y84037D02*
X133306Y85802D01*
G01X128721Y79255D02*
X129955Y81018D01*
G01X125373Y74473D02*
X126607Y76236D01*
G01X122025Y69691D02*
X123259Y71454D01*
G01X116843Y62291D02*
X119911Y66672D01*
G01X115078Y61055D02*
X116843Y62291D01*
G01X114108Y61228D02*
X115078Y61055D01*
G01X139070Y118489D02*
X113264Y264844D01*
G01X140492Y118490D02*
X114589Y265393D01*
G01X135607Y98857D02*
X139070Y118489D01*
G01X134631Y85253D02*
X140492Y118490D01*
G01X134573Y92995D02*
X134948Y95113D01*
G01X134631Y85253D02*
X140492Y118490D01*
G01X133306Y85802D02*
X133914Y89251D01*
G01X134631Y85253D02*
X140492Y118490D01*
G01X132069Y84037D02*
X133306Y85802D01*
G01X117849Y61285D02*
X134631Y85253D01*
G01X128721Y79255D02*
X129955Y81018D01*
G01X117849Y61285D02*
X134631Y85253D01*
G01X125373Y74473D02*
X126607Y76236D01*
G01X117849Y61285D02*
X134631Y85253D01*
G01X122025Y69691D02*
X123259Y71454D01*
G01X117849Y61285D02*
X134631Y85253D01*
G01X116843Y62291D02*
X119911Y66672D01*
G01X117849Y61285D02*
X134631Y85253D01*
G01X115078Y61055D02*
X116843Y62291D01*
G01X114108Y61228D02*
X115078Y61055D01*
G01X130006Y88278D02*
X135898Y121694D01*
G01X132501Y110493D02*
X134475Y121689D01*
G01X131566Y105195D02*
X131905Y107115D01*
G01X130632Y99897D02*
X130971Y101817D01*
G01X129698Y94599D02*
X130037Y96519D01*
G01X128681Y88827D02*
X129103Y91221D01*
G01X126810Y83716D02*
X130006Y88278D01*
G01X125808Y84727D02*
X128681Y88827D01*
G01X115881Y76047D02*
X126810Y83716D01*
G01X115331Y77373D02*
X125808Y84727D01*
G01X132501Y110493D02*
X134475Y121689D01*
G01X130006Y88278D02*
X135898Y121694D01*
G01X131566Y105195D02*
X131905Y107115D01*
G01X130006Y88278D02*
X135898Y121694D01*
G01X130632Y99897D02*
X130971Y101817D01*
G01X130006Y88278D02*
X135898Y121694D01*
G01X129698Y94599D02*
X130037Y96519D01*
G01X130006Y88278D02*
X135898Y121694D01*
G01X128681Y88827D02*
X129103Y91221D01*
G01X130006Y88278D02*
X135898Y121694D01*
G01X125808Y84727D02*
X128681Y88827D01*
G01X126810Y83716D02*
X130006Y88278D01*
G01X115331Y77373D02*
X125808Y84727D01*
G01X115881Y76047D02*
X126810Y83716D01*
G01X119618Y99426D02*
X112607Y94519D01*
G01X118612Y100432D02*
X112058Y95844D01*
G01X128694Y112388D02*
X119618Y99426D01*
G01X119731Y102029D02*
X118612Y100432D01*
G01X122817Y106436D02*
X121698Y104839D01*
G01X127369Y112937D02*
X124784Y109246D01*
G01X131164Y126390D02*
X128694Y112388D01*
G01X129742Y126390D02*
X127369Y112937D01*
G01X118612Y100432D02*
X112058Y95844D01*
G01X119618Y99426D02*
X112607Y94519D01*
G01X119731Y102029D02*
X118612Y100432D01*
G01X128694Y112388D02*
X119618Y99426D01*
G01X122817Y106436D02*
X121698Y104839D01*
G01X128694Y112388D02*
X119618Y99426D01*
G01X127369Y112937D02*
X124784Y109246D01*
G01X128694Y112388D02*
X119618Y99426D01*
G01X129742Y126390D02*
X127369Y112937D01*
G01X131164Y126390D02*
X128694Y112388D01*
G01X128200Y135131D02*
X129742Y126390D01*
G01X127266Y140429D02*
X127605Y138509D01*
G01X126332Y145727D02*
X126671Y143807D01*
G01X125398Y151025D02*
X125737Y149105D01*
G01X128200Y135131D02*
X129742Y126390D01*
G01X127266Y140429D02*
X127605Y138509D01*
G01X126332Y145727D02*
X126671Y143807D01*
G01X125398Y151025D02*
X125737Y149105D01*
G01X116390Y146471D02*
X113883Y144716D01*
G01X115384Y147477D02*
X113334Y146041D01*
G01X119221Y150515D02*
X116390Y146471D01*
G01X117896Y151064D02*
X115384Y147477D01*
G01X121093Y161136D02*
X119221Y150515D01*
G01X119671Y161136D02*
X117896Y151064D01*
G01X115501Y184790D02*
X119671Y161136D01*
G01X114566Y190090D02*
X114905Y188170D01*
G01X115384Y147477D02*
X113334Y146041D01*
G01X116390Y146471D02*
X113883Y144716D01*
G01X117896Y151064D02*
X115384Y147477D01*
G01X119221Y150515D02*
X116390Y146471D01*
G01X119671Y161136D02*
X117896Y151064D01*
G01X121093Y161136D02*
X119221Y150515D01*
G01X115501Y184790D02*
X119671Y161136D01*
G01X114566Y190090D02*
X114905Y188170D01*
G01X125865Y237764D02*
X119577Y273420D01*
G01X124540Y237215D02*
X118252Y272871D01*
G01X131196Y230149D02*
X125865Y237764D01*
G01X130190Y229143D02*
X124540Y237215D01*
G01X135207Y227341D02*
X131196Y230149D01*
G01X134658Y226016D02*
X130190Y229143D01*
G01X139154Y226645D02*
X135207Y227341D01*
G01X139031Y225245D02*
X134658Y226016D01*
G01X143095Y226645D02*
X139154D01*
G01X143095Y225245D02*
X139031D01*
G01X124540Y237215D02*
X118252Y272871D01*
G01X125865Y237764D02*
X119577Y273420D01*
G01X130190Y229143D02*
X124540Y237215D01*
G01X131196Y230149D02*
X125865Y237764D01*
G01X134658Y226016D02*
X130190Y229143D01*
G01X135207Y227341D02*
X131196Y230149D01*
G01X139031Y225245D02*
X134658Y226016D01*
G01X139154Y226645D02*
X135207Y227341D01*
G01X143095Y225245D02*
X139031D01*
G01X143095Y226645D02*
X139154D01*
G01X139488Y314834D02*
X116170Y318945D01*
G01X139365Y313434D02*
X115621Y317620D01*
G01X143095Y314834D02*
X139488D01*
G01X143095Y313434D02*
X139365D01*
G01D02*
X115621Y317620D01*
G01X139488Y314834D02*
X116170Y318945D01*
G01X143095Y313434D02*
X139365D01*
G01X143095Y314834D02*
X139488D01*
G01X139154Y295937D02*
X143096D01*
G01X139031Y294537D02*
X143094D01*
G01X122187Y298929D02*
X139154Y295937D01*
G01X130427Y296054D02*
X139031Y294537D01*
G01X121796Y297576D02*
X130427Y296054D01*
G01X116694Y301176D02*
X122187Y298929D01*
G01X116019Y299939D02*
X121796Y297576D01*
G01X139031Y294537D02*
X143094D01*
G01X139154Y295937D02*
X143096D01*
G01X130427Y296054D02*
X139031Y294537D01*
G01X122187Y298929D02*
X139154Y295937D01*
G01X121796Y297576D02*
X130427Y296054D01*
G01X122187Y298929D02*
X139154Y295937D01*
G01X116019Y299939D02*
X121796Y297576D01*
G01X116694Y301176D02*
X122187Y298929D01*
G01X139693Y277039D02*
X143096D01*
G01X143094Y275639D02*
X139570D01*
G01X129712Y278799D02*
X139693Y277039D01*
G01X139570Y275639D02*
X129163Y277474D01*
G01X139570Y275639D02*
X129163Y277474D01*
G01X129712Y278799D02*
X139693Y277039D01*
G01X143094Y275639D02*
X139570D01*
G01X139693Y277039D02*
X143096D01*
G01X177685Y405322D02*
X180127Y419167D01*
G01X176360Y405871D02*
X178705Y419167D01*
G01X172468Y397869D02*
X177685Y405322D01*
G01X171462Y398875D02*
X176360Y405871D01*
G01X159881Y389056D02*
X172468Y397869D01*
G01X159332Y390381D02*
X171462Y398875D01*
G01X176360Y405871D02*
X178705Y419167D01*
G01X177685Y405322D02*
X180127Y419167D01*
G01X171462Y398875D02*
X176360Y405871D01*
G01X172468Y397869D02*
X177685Y405322D01*
G01X159332Y390381D02*
X171462Y398875D01*
G01X159881Y389056D02*
X172468Y397869D01*
G01X169604Y400563D02*
X158639Y392887D01*
G01X168598Y401569D02*
X158090Y394212D01*
G01X174135Y407036D02*
X169604Y400563D01*
G01X172810Y407585D02*
X168598Y401569D01*
G01X176171Y418584D02*
X174135Y407036D01*
G01X174749Y418584D02*
X172810Y407585D01*
G01X168598Y401569D02*
X158090Y394212D01*
G01X169604Y400563D02*
X158639Y392887D01*
G01X172810Y407585D02*
X168598Y401569D01*
G01X174135Y407036D02*
X169604Y400563D01*
G01X174749Y418584D02*
X172810Y407585D01*
G01X176171Y418584D02*
X174135Y407036D01*
G01X167497Y403839D02*
X157052Y396526D01*
G01X156503Y397851D02*
X166491Y404845D01*
G01X170584Y408249D02*
X167497Y403839D01*
G01X166491Y404845D02*
X169259Y408798D01*
G01X172304Y418000D02*
X170584Y408249D01*
G01X169259Y408798D02*
X170882Y418000D01*
G01X169259Y408798D02*
X170882Y418000D01*
G01X172304D02*
X170584Y408249D01*
G01X166491Y404845D02*
X169259Y408798D01*
G01X170584Y408249D02*
X167497Y403839D01*
G01X156503Y397851D02*
X166491Y404845D01*
G01X167497Y403839D02*
X157052Y396526D01*
G01X166916Y409294D02*
X168451Y418001D01*
G01X165591Y409843D02*
X167029Y418001D01*
G01X164839Y406328D02*
X166916Y409294D01*
G01X163833Y407334D02*
X165591Y409843D01*
G01X155903Y400072D02*
X164839Y406328D01*
G01X155354Y401397D02*
X163833Y407334D01*
G01X165591Y409843D02*
X167029Y418001D01*
G01X166916Y409294D02*
X168451Y418001D01*
G01X163833Y407334D02*
X165591Y409843D01*
G01X164839Y406328D02*
X166916Y409294D01*
G01X155354Y401397D02*
X163833Y407334D01*
G01X155903Y400072D02*
X164839Y406328D01*
G01X166637Y456602D02*
X145211Y578050D01*
G01X165312Y456053D02*
X143886Y577501D01*
G01X175844Y443453D02*
X166637Y456602D01*
G01X174519Y442904D02*
X165312Y456053D01*
G01X180127Y419167D02*
X175844Y443453D01*
G01X178705Y419167D02*
X174519Y442904D01*
G01X165312Y456053D02*
X143886Y577501D01*
G01X166637Y456602D02*
X145211Y578050D01*
G01X174519Y442904D02*
X165312Y456053D01*
G01X175844Y443453D02*
X166637Y456602D01*
G01X178705Y419167D02*
X174519Y442904D01*
G01X180127Y419167D02*
X175844Y443453D01*
G01X171916Y442706D02*
X176171Y418584D01*
G01X170591Y442157D02*
X174749Y418584D01*
G01X162977Y455473D02*
X171916Y442706D01*
G01X161652Y454924D02*
X170591Y442157D01*
G01X141414Y577041D02*
X162977Y455473D01*
G01X140089Y576492D02*
X161652Y454924D01*
G01X170591Y442157D02*
X174749Y418584D01*
G01X171916Y442706D02*
X176171Y418584D01*
G01X161652Y454924D02*
X170591Y442157D01*
G01X162977Y455473D02*
X171916Y442706D01*
G01X140089Y576492D02*
X161652Y454924D01*
G01X141414Y577041D02*
X162977Y455473D01*
G01X168074Y441981D02*
X172304Y418000D01*
G01X170882D02*
X166749Y441432D01*
G01X159341Y454453D02*
X168074Y441981D01*
G01X166749Y441432D02*
X158016Y453904D01*
G01X138044Y575213D02*
X159341Y454453D01*
G01X158016Y453904D02*
X136718Y574664D01*
G01X158016Y453904D02*
X136718Y574664D01*
G01X138044Y575213D02*
X159341Y454453D01*
G01X166749Y441432D02*
X158016Y453904D01*
G01X159341Y454453D02*
X168074Y441981D01*
G01X170882Y418000D02*
X166749Y441432D01*
G01X168074Y441981D02*
X172304Y418000D01*
G01X155837Y452886D02*
X134559Y573561D01*
G01X154512Y452337D02*
X133233Y573012D01*
G01X164473Y440554D02*
X155837Y452886D01*
G01X163148Y440005D02*
X154512Y452337D01*
G01X168451Y418001D02*
X164473Y440554D01*
G01X167029Y418001D02*
X163148Y440005D01*
G01X154512Y452337D02*
X133233Y573012D01*
G01X155837Y452886D02*
X134559Y573561D01*
G01X163148Y440005D02*
X154512Y452337D01*
G01X164473Y440554D02*
X155837Y452886D01*
G01X167029Y418001D02*
X163148Y440005D01*
G01X168451Y418001D02*
X164473Y440554D01*
G01X119268Y468787D02*
X134622Y490713D01*
G01X126006Y480851D02*
X127125Y482448D01*
G01X118262Y469793D02*
X124038Y478042D01*
G01X116665Y468675D02*
X118262Y469793D01*
G01X115634Y468857D02*
X116665Y468675D01*
G01X119268Y468787D02*
X134622Y490713D01*
G01X119268Y468787D02*
X134622Y490713D01*
G01X126006Y480851D02*
X127125Y482448D01*
G01X119268Y468787D02*
X134622Y490713D01*
G01X118262Y469793D02*
X124038Y478042D01*
G01X119268Y468787D02*
X134622Y490713D01*
G01X116665Y468675D02*
X118262Y469793D01*
G01X115634Y468857D02*
X116665Y468675D01*
G01X138201Y511009D02*
X126674Y576384D01*
G01X136779Y511009D02*
X125349Y575834D01*
G01X134622Y490713D02*
X138201Y511009D01*
G01X133297Y491262D02*
X136779Y511009D01*
G01X132178Y489665D02*
X133297Y491262D01*
G01X129092Y485258D02*
X130211Y486855D01*
G01X136779Y511009D02*
X125349Y575834D01*
G01X138201Y511009D02*
X126674Y576384D01*
G01X133297Y491262D02*
X136779Y511009D01*
G01X134622Y490713D02*
X138201Y511009D01*
G01X132178Y489665D02*
X133297Y491262D01*
G01X129092Y485258D02*
X130211Y486855D01*
G01X112077Y484620D02*
X120033Y490193D01*
G01X131939Y504754D02*
X121039Y489187D01*
G01X129291Y503414D02*
X130614Y505303D01*
G01X126205Y499007D02*
X127324Y500604D01*
G01X123119Y494600D02*
X124238Y496197D01*
G01X120033Y490193D02*
X121152Y491790D01*
G01X133683Y514647D02*
X131939Y504754D01*
G01X130614Y505303D02*
X132261Y514647D01*
G01X122991Y575286D02*
X133683Y514647D01*
G01X132261D02*
X121666Y574737D01*
G01X132261Y514647D02*
X121666Y574737D01*
G01X122991Y575286D02*
X133683Y514647D01*
G01X130614Y505303D02*
X132261Y514647D01*
G01X133683D02*
X131939Y504754D01*
G01X129291Y503414D02*
X130614Y505303D01*
G01X131939Y504754D02*
X121039Y489187D01*
G01X126205Y499007D02*
X127324Y500604D01*
G01X131939Y504754D02*
X121039Y489187D01*
G01X123119Y494600D02*
X124238Y496197D01*
G01X131939Y504754D02*
X121039Y489187D01*
G01X120033Y490193D02*
X121152Y491790D01*
G01X131939Y504754D02*
X121039Y489187D01*
G01X112077Y484620D02*
X120033Y490193D01*
G01X122651Y554804D02*
X119258Y574046D01*
G01X117933Y573497D02*
X121229Y554804D01*
G01X116864Y522003D02*
X122651Y554804D01*
G01X115809Y524084D02*
X115442Y522003D01*
G01X116726Y529281D02*
X116405Y527462D01*
G01X121229Y554804D02*
X116726Y529281D01*
G01X118350Y513572D02*
X116864Y522003D01*
G01X115442D02*
X116928Y513572D01*
G01X117033Y506105D02*
X118350Y513572D01*
G01X116928D02*
X115708Y506654D01*
G01X114506Y502494D02*
X117033Y506105D01*
G01X115708Y506654D02*
X113500Y503500D01*
G01X115708Y506654D02*
X113500Y503500D01*
G01X114506Y502494D02*
X117033Y506105D01*
G01X116928Y513572D02*
X115708Y506654D01*
G01X117033Y506105D02*
X118350Y513572D01*
G01X115442Y522003D02*
X116928Y513572D01*
G01X118350D02*
X116864Y522003D01*
G01X115809Y524084D02*
X115442Y522003D01*
G01X116864D02*
X122651Y554804D01*
G01X116726Y529281D02*
X116405Y527462D01*
G01X116864Y522003D02*
X122651Y554804D01*
G01X121229D02*
X116726Y529281D01*
G01X116864Y522003D02*
X122651Y554804D01*
G01X117933Y573497D02*
X121229Y554804D01*
G01X122651D02*
X119258Y574046D01*
G01X130694Y598785D02*
X116785Y677670D01*
G01X129369Y598236D02*
X115460Y677121D01*
G01X145211Y578050D02*
X130694Y598785D01*
G01X143886Y577501D02*
X129369Y598236D01*
G01D02*
X115460Y677121D01*
G01X130694Y598785D02*
X116785Y677670D01*
G01X143886Y577501D02*
X129369Y598236D01*
G01X145211Y578050D02*
X130694Y598785D01*
G01X127098Y597493D02*
X141414Y577041D01*
G01X125773Y596944D02*
X140089Y576492D01*
G01X113327Y675608D02*
X127098Y597493D01*
G01X112002Y675059D02*
X125773Y596944D01*
G01D02*
X140089Y576492D01*
G01X127098Y597493D02*
X141414Y577041D01*
G01X112002Y675059D02*
X125773Y596944D01*
G01X113327Y675608D02*
X127098Y597493D01*
G01X123595Y595849D02*
X138044Y575213D01*
G01X135805Y575969D02*
X122270Y595300D01*
G01X136267Y575309D02*
X135805Y575969D01*
G01X136718Y574664D02*
X136267Y575309D01*
G01X135805Y575969D02*
X122270Y595300D01*
G01X123595Y595849D02*
X138044Y575213D01*
G01X136267Y575309D02*
X135805Y575969D01*
G01X123595Y595849D02*
X138044Y575213D01*
G01X136718Y574664D02*
X136267Y575309D01*
G01X123595Y595849D02*
X138044Y575213D01*
G01X134289Y573946D02*
X119889Y594511D01*
G01X133233Y573012D02*
X118564Y593962D01*
G01X134559Y573561D02*
X134289Y573946D01*
G01X133233Y573012D02*
X118564Y593962D01*
G01X133233Y573012D02*
X118564Y593962D01*
G01X134289Y573946D02*
X119889Y594511D01*
G01X134559Y573561D02*
X134289Y573946D01*
G01X115275Y592662D02*
X115159Y593326D01*
G01X126674Y576384D02*
X115275Y592662D01*
G01X125349Y575834D02*
X113950Y592113D01*
G01X115275Y592662D02*
X115159Y593326D01*
G01X125349Y575834D02*
X113950Y592113D01*
G01X126674Y576384D02*
X115275Y592662D01*
G01X116815Y575094D02*
X117933Y573497D01*
G01X113729Y579501D02*
X114847Y577904D01*
G01X116815Y575094D02*
X117933Y573497D01*
G01X113729Y579501D02*
X114847Y577904D01*
G01X139154Y701449D02*
X143096D01*
G01X139031Y700049D02*
X143094D01*
G01X134446Y702279D02*
X139154Y701449D01*
G01X134203Y700900D02*
X139031Y700049D01*
G01X133968Y702363D02*
X134446Y702279D01*
G01X134203Y700900D02*
X139031Y700049D01*
G01X127148Y702143D02*
X134203Y700900D01*
G01X127391Y703522D02*
X133968Y702363D01*
G01X127148Y702143D02*
X134203Y700900D01*
G01X118350Y703693D02*
X127148Y702143D01*
G01X139031Y700049D02*
X143094D01*
G01X139154Y701449D02*
X143096D01*
G01X134203Y700900D02*
X139031Y700049D01*
G01X134446Y702279D02*
X139154Y701449D01*
G01X133968Y702363D02*
X134446Y702279D01*
G01X127148Y702143D02*
X134203Y700900D01*
G01X133968Y702363D02*
X134446Y702279D01*
G01X127391Y703522D02*
X133968Y702363D01*
G01X118350Y703693D02*
X127148Y702143D01*
G01X131903Y683926D02*
X113772Y696621D01*
G01X131354Y682601D02*
X112766Y695615D01*
G01X139693Y682551D02*
X131903Y683926D01*
G01X139570Y681151D02*
X131354Y682601D01*
G01X143096Y682551D02*
X139693D01*
G01X143094Y681151D02*
X139570D01*
G01X131354Y682601D02*
X112766Y695615D01*
G01X131903Y683926D02*
X113772Y696621D01*
G01X139570Y681151D02*
X131354Y682601D01*
G01X139693Y682551D02*
X131903Y683926D01*
G01X143094Y681151D02*
X139570D01*
G01X143096Y682551D02*
X139693D01*
G01X127810Y643372D02*
X121551Y678870D01*
G01X126485Y642823D02*
X120226Y678321D01*
G01X133974Y634569D02*
X127810Y643372D01*
G01X132968Y633563D02*
X126485Y642823D01*
G01X136832Y632567D02*
X133974Y634569D01*
G01X136283Y631242D02*
X132968Y633563D01*
G01X139154Y632157D02*
X136832Y632567D01*
G01X139031Y630757D02*
X136283Y631242D01*
G01X143095Y632157D02*
X139154D01*
G01X143095Y630757D02*
X139031D01*
G01X126485Y642823D02*
X120226Y678321D01*
G01X127810Y643372D02*
X121551Y678870D01*
G01X132968Y633563D02*
X126485Y642823D01*
G01X133974Y634569D02*
X127810Y643372D01*
G01X136283Y631242D02*
X132968Y633563D01*
G01X136832Y632567D02*
X133974Y634569D01*
G01X139031Y630757D02*
X136283Y631242D01*
G01X139154Y632157D02*
X136832Y632567D01*
G01X143095Y630757D02*
X139031D01*
G01X143095Y632157D02*
X139154D01*
G01X143095Y720346D02*
X139488D01*
G01X143095Y718946D02*
X139365D01*
G01X143095D02*
X139365D01*
G01X143095Y720346D02*
X139488D01*
G01X118899Y705018D02*
X127391Y703522D01*
G01X118899Y705018D02*
X127391Y703522D01*
G01X135628Y801548D02*
X133708Y801209D01*
G01X140926Y802482D02*
X139006Y802143D01*
G01X149206Y803942D02*
X144304Y803078D01*
G01X160000Y811500D02*
X149206Y803942D01*
G01X161006Y810494D02*
X149755Y802617D01*
G01X163876Y817036D02*
X160000Y811500D01*
G01X165201Y816487D02*
X161006Y810494D01*
G01X164965Y823213D02*
X163876Y817036D01*
G01X166387Y823213D02*
X165201Y816487D01*
G01X163287Y832727D02*
X164965Y823213D01*
G01X164612Y833276D02*
X166387Y823213D01*
G01X159564Y838045D02*
X163287Y832727D01*
G01X160570Y839051D02*
X164612Y833276D01*
G01X151934Y843386D02*
X159564Y838045D01*
G01X152483Y844711D02*
X160570Y839051D01*
G01X121967Y848671D02*
X151934Y843386D01*
G01X122516Y849996D02*
X152483Y844711D01*
G01X135628Y801548D02*
X133708Y801209D01*
G01X140926Y802482D02*
X139006Y802143D01*
G01X149206Y803942D02*
X144304Y803078D01*
G01X161006Y810494D02*
X149755Y802617D01*
G01X160000Y811500D02*
X149206Y803942D01*
G01X165201Y816487D02*
X161006Y810494D01*
G01X163876Y817036D02*
X160000Y811500D01*
G01X166387Y823213D02*
X165201Y816487D01*
G01X164965Y823213D02*
X163876Y817036D01*
G01X164612Y833276D02*
X166387Y823213D01*
G01X163287Y832727D02*
X164965Y823213D01*
G01X160570Y839051D02*
X164612Y833276D01*
G01X159564Y838045D02*
X163287Y832727D01*
G01X152483Y844711D02*
X160570Y839051D01*
G01X151934Y843386D02*
X159564Y838045D01*
G01X122516Y849996D02*
X152483Y844711D01*
G01X121967Y848671D02*
X151934Y843386D01*
G01X166961Y834057D02*
X150227Y857958D01*
G01X168286Y834606D02*
X151233Y858964D01*
G01X168764Y823833D02*
X166961Y834057D01*
G01X170186Y823833D02*
X168286Y834606D01*
G01X167192Y814916D02*
X168764Y823833D01*
G01X168517Y814367D02*
X170186Y823833D01*
G01X162754Y808578D02*
X167192Y814916D01*
G01X163760Y807572D02*
X168517Y814367D01*
G01X151440Y800656D02*
X162754Y808578D01*
G01X151989Y799331D02*
X163760Y807572D01*
G01X168286Y834606D02*
X151233Y858964D01*
G01X166961Y834057D02*
X150227Y857958D01*
G01X170186Y823833D02*
X168286Y834606D01*
G01X168764Y823833D02*
X166961Y834057D01*
G01X168517Y814367D02*
X170186Y823833D01*
G01X167192Y814916D02*
X168764Y823833D01*
G01X163760Y807572D02*
X168517Y814367D01*
G01X162754Y808578D02*
X167192Y814916D01*
G01X151989Y799331D02*
X163760Y807572D01*
G01X151440Y800656D02*
X162754Y808578D01*
G01X164724Y805108D02*
X153298Y797107D01*
G01X165730Y804102D02*
X153847Y795782D01*
G01X171175Y814319D02*
X164724Y805108D01*
G01X172500Y813770D02*
X165730Y804102D01*
G01X172852Y823833D02*
X171175Y814319D01*
G01X174274Y823833D02*
X172500Y813770D01*
G01X170876Y835038D02*
X172852Y823833D01*
G01X172201Y835587D02*
X174274Y823833D01*
G01X146070Y870464D02*
X170876Y835038D01*
G01X136800Y886145D02*
X172201Y835587D01*
G01X136800Y886145D02*
X172201Y835587D01*
G01X136800Y886145D02*
X172201Y835587D01*
G01X136800Y886145D02*
X172201Y835587D01*
G01X165730Y804102D02*
X153847Y795782D01*
G01X164724Y805108D02*
X153298Y797107D01*
G01X172500Y813770D02*
X165730Y804102D01*
G01X171175Y814319D02*
X164724Y805108D01*
G01X174274Y823833D02*
X172500Y813770D01*
G01X172852Y823833D02*
X171175Y814319D01*
G01X172201Y835587D02*
X174274Y823833D01*
G01X170876Y835038D02*
X172852Y823833D01*
G01X136800Y886145D02*
X172201Y835587D01*
G01X146070Y870464D02*
X170876Y835038D01*
G01X174404Y836714D02*
X120095Y914279D01*
G01X121420Y914828D02*
X175729Y837263D01*
G01X176646Y824000D02*
X174404Y836714D01*
G01X175729Y837263D02*
X178068Y824000D01*
G01X174590Y812340D02*
X176646Y824000D01*
G01X178068D02*
X175915Y811791D01*
G01X167892Y802776D02*
X174590Y812340D01*
G01X175915Y811791D02*
X168898Y801770D01*
G01X155014Y793758D02*
X167892Y802776D01*
G01X168898Y801770D02*
X155563Y792433D01*
G01X168898Y801770D02*
X155563Y792433D01*
G01X155014Y793758D02*
X167892Y802776D01*
G01X175915Y811791D02*
X168898Y801770D01*
G01X167892Y802776D02*
X174590Y812340D01*
G01X178068Y824000D02*
X175915Y811791D01*
G01X174590Y812340D02*
X176646Y824000D01*
G01X175729Y837263D02*
X178068Y824000D01*
G01X176646D02*
X174404Y836714D01*
G01X121420Y914828D02*
X175729Y837263D01*
G01X174404Y836714D02*
X120095Y914279D01*
G01X150502Y952821D02*
X226722Y843949D01*
G01X149177Y952272D02*
X225716Y842943D01*
G01X149177Y952272D02*
X225716Y842943D01*
G01X150502Y952821D02*
X226722Y843949D01*
G01X220992Y841708D02*
X147857Y946132D01*
G01X219986Y840702D02*
X146532Y945583D01*
G01X219986Y840702D02*
X146532Y945583D01*
G01X220992Y841708D02*
X147857Y946132D01*
G01X144267Y944975D02*
X218421Y839072D01*
G01X142942Y944426D02*
X217415Y838066D01*
G01X142942Y944426D02*
X217415Y838066D01*
G01X144267Y944975D02*
X218421Y839072D01*
G01X136241Y941791D02*
X352121Y633496D01*
G01X134916Y941242D02*
X351115Y632490D01*
G01X134916Y941242D02*
X351115Y632490D01*
G01X136241Y941791D02*
X352121Y633496D01*
G01X350037Y630199D02*
X132331Y941112D01*
G01X349031Y629193D02*
X131006Y940563D01*
G01X349031Y629193D02*
X131006Y940563D01*
G01X350037Y630199D02*
X132331Y941112D01*
G01X215736Y836478D02*
X140873Y943394D01*
G01X214730Y835472D02*
X139548Y942845D01*
G01X214730Y835472D02*
X139548Y942845D01*
G01X215736Y836478D02*
X140873Y943394D01*
G01X113583Y854544D02*
X121967Y848671D01*
G01X114552Y855575D02*
X122516Y849996D01*
G01X114552Y855575D02*
X122516Y849996D01*
G01X113583Y854544D02*
X121967Y848671D01*
G01X114592Y882910D02*
X112995Y884028D01*
G01X151233Y858964D02*
X113544Y885353D01*
G01X117402Y880942D02*
X116371Y880760D01*
G01X151233Y858964D02*
X113544Y885353D01*
G01X118999Y879824D02*
X117402Y880942D01*
G01X151233Y858964D02*
X113544Y885353D01*
G01X121809Y877856D02*
X120778Y877675D01*
G01X151233Y858964D02*
X113544Y885353D01*
G01X123406Y876738D02*
X121809Y877856D01*
G01X151233Y858964D02*
X113544Y885353D01*
G01X126216Y874770D02*
X125185Y874589D01*
G01X151233Y858964D02*
X113544Y885353D01*
G01X142599Y863299D02*
X126216Y874770D01*
G01X151233Y858964D02*
X113544Y885353D01*
G01X145409Y861332D02*
X144378Y861150D01*
G01X151233Y858964D02*
X113544Y885353D01*
G01X150227Y857958D02*
X145409Y861332D01*
G01X151233Y858964D02*
X113544Y885353D01*
G01X151233Y858964D02*
X113544Y885353D01*
G01X114592Y882910D02*
X112995Y884028D01*
G01X117402Y880942D02*
X116371Y880760D01*
G01X118999Y879824D02*
X117402Y880942D01*
G01X121809Y877856D02*
X120778Y877675D01*
G01X123406Y876738D02*
X121809Y877856D01*
G01X126216Y874770D02*
X125185Y874589D01*
G01X142599Y863299D02*
X126216Y874770D01*
G01X145409Y861332D02*
X144378Y861150D01*
G01X150227Y857958D02*
X145409Y861332D01*
G01X347098Y627555D02*
X128921Y939144D01*
G01X346092Y626549D02*
X127596Y938595D01*
G01X346092Y626549D02*
X127596Y938595D01*
G01X347098Y627555D02*
X128921Y939144D01*
G01X142984Y874871D02*
X144102Y873274D01*
G01X139898Y879278D02*
X141016Y877681D01*
G01X135794Y885139D02*
X137930Y882088D01*
G01X123458Y893776D02*
X135794Y885139D01*
G01X122427Y893595D02*
X123458Y893776D01*
G01X119051Y896862D02*
X120648Y895744D01*
G01X118020Y896681D02*
X119051Y896862D01*
G01X114644Y899948D02*
X116241Y898830D01*
G01X113613Y899766D02*
X114644Y899948D01*
G01X142984Y874871D02*
X144102Y873274D01*
G01X139898Y879278D02*
X141016Y877681D01*
G01X135794Y885139D02*
X137930Y882088D01*
G01X123458Y893776D02*
X135794Y885139D01*
G01X122427Y893595D02*
X123458Y893776D01*
G01X119051Y896862D02*
X120648Y895744D01*
G01X118020Y896681D02*
X119051Y896862D01*
G01X114644Y899948D02*
X116241Y898830D01*
G01X113613Y899766D02*
X114644Y899948D01*
G01X344972Y624138D02*
X125337Y937722D01*
G01X343966Y623132D02*
X124012Y937173D01*
G01X343966Y623132D02*
X124012Y937173D01*
G01X344972Y624138D02*
X125337Y937722D01*
G01X118672Y930417D02*
X121420Y914828D01*
G01X119161Y919577D02*
X118822Y921498D01*
G01X118672Y930417D02*
X121420Y914828D01*
G01X120095Y914279D02*
X119756Y916199D01*
G01X118672Y930417D02*
X121420Y914828D01*
G01X118672Y930417D02*
X121420Y914828D01*
G01X119161Y919577D02*
X118822Y921498D01*
G01X120095Y914279D02*
X119756Y916199D01*
G01X145033Y983819D02*
X150502Y952821D01*
G01X143708Y983270D02*
X149177Y952272D01*
G01X126625Y1010106D02*
X145033Y983819D01*
G01X134682Y996159D02*
X143708Y983270D01*
G01D02*
X149177Y952272D01*
G01X145033Y983819D02*
X150502Y952821D01*
G01X134682Y996159D02*
X143708Y983270D01*
G01X126625Y1010106D02*
X145033Y983819D01*
G01X126625Y1010106D02*
X145033Y983819D01*
G01X126625Y1010106D02*
X145033Y983819D01*
G01X141273Y982760D02*
X122955Y1008920D01*
G01X140117Y981970D02*
X121630Y1008371D01*
G01X141448Y982510D02*
X141273Y982761D01*
G01X140117Y981970D02*
X121630Y1008371D01*
G01X147857Y946132D02*
X141448Y982510D01*
G01X146532Y945583D02*
X140123Y981961D01*
G01X140117Y981970D02*
X121630Y1008371D01*
G01X141273Y982760D02*
X122955Y1008920D01*
G01X141448Y982510D02*
X141273Y982761D01*
G01X146532Y945583D02*
X140123Y981961D01*
G01X147857Y946132D02*
X141448Y982510D01*
G01X137934Y980882D02*
X144267Y944975D01*
G01X136609Y980333D02*
X142942Y944426D01*
G01X137756Y981137D02*
X137934Y980882D01*
G01X118079Y1006796D02*
X136609Y980333D01*
G01X119404Y1007345D02*
X137756Y981136D01*
G01X118079Y1006796D02*
X136609Y980333D01*
G01D02*
X142942Y944426D01*
G01X137934Y980882D02*
X144267Y944975D01*
G01X118079Y1006796D02*
X136609Y980333D01*
G01X137756Y981137D02*
X137934Y980882D01*
G01X119404Y1007345D02*
X137756Y981136D01*
G01X130007Y977135D02*
X136241Y941791D01*
G01X128682Y976586D02*
X134916Y941242D01*
G01X128682Y976586D02*
X134916Y941242D01*
G01X130007Y977135D02*
X136241Y941791D01*
G01X132331Y941112D02*
X126170Y976044D01*
G01X131006Y940563D02*
X124845Y975495D01*
G01X131006Y940563D02*
X124845Y975495D01*
G01X132331Y941112D02*
X126170Y976044D01*
G01X134556Y979205D02*
X115860Y1005909D01*
G01X133231Y978656D02*
X114535Y1005360D01*
G01X140873Y943394D02*
X134556Y979205D01*
G01X139548Y942845D02*
X133231Y978656D01*
G01D02*
X114535Y1005360D01*
G01X134556Y979205D02*
X115860Y1005909D01*
G01X139548Y942845D02*
X133231Y978656D01*
G01X140873Y943394D02*
X134556Y979205D01*
G01X122633Y974813D02*
X117681Y981884D01*
G01X121308Y974264D02*
X116675Y980878D01*
G01X128921Y939144D02*
X122633Y974813D01*
G01X127596Y938595D02*
X121308Y974264D01*
G01D02*
X116675Y980878D01*
G01X122633Y974813D02*
X117681Y981884D01*
G01X127596Y938595D02*
X121308Y974264D01*
G01X128921Y939144D02*
X122633Y974813D01*
G01X120190Y966940D02*
X115746Y973290D01*
G01X118864Y966391D02*
X114755Y972264D01*
G01X125337Y937722D02*
X120190Y966940D01*
G01X124012Y937173D02*
X118864Y966391D01*
G01D02*
X114755Y972264D01*
G01X120190Y966940D02*
X115746Y973290D01*
G01X124012Y937173D02*
X118864Y966391D01*
G01X125337Y937722D02*
X120190Y966940D01*
G01X114956Y943419D02*
X111568Y948256D01*
G01X117292Y930174D02*
X114956Y943419D01*
G01X116281Y943968D02*
X118671Y930417D01*
G01X118226Y924875D02*
X117887Y926796D01*
G01X118226Y924875D02*
X117887Y926796D01*
G01X116281Y943968D02*
X118671Y930417D01*
G01X117292Y930174D02*
X114956Y943419D01*
G01D02*
X111568Y948256D01*
G01X128260Y1005330D02*
X134682Y996159D01*
G01X125300Y1009557D02*
X128260Y1005330D01*
G01X113821Y1082710D02*
X126625Y1010106D01*
G01X112496Y1082160D02*
X125300Y1009557D01*
G01X128260Y1005330D02*
X134682Y996159D01*
G01X125300Y1009557D02*
X128260Y1005330D01*
G01X112496Y1082160D02*
X125300Y1009557D01*
G01X113821Y1082710D02*
X126625Y1010106D01*
G01X125077Y1045474D02*
X117837Y1086534D01*
G01X123752Y1044925D02*
X116512Y1085985D01*
G01X127506Y1042006D02*
X125077Y1045474D01*
G01X126500Y1041000D02*
X123752Y1044925D01*
G01X131819Y1038985D02*
X127506Y1042006D01*
G01X131270Y1037660D02*
X126500Y1041000D01*
G01X139277Y1037669D02*
X131819Y1038985D01*
G01X135304Y1036948D02*
X131270Y1037660D01*
G01X139154Y1036269D02*
X135304Y1036948D01*
G01X143095Y1037669D02*
X139277D01*
G01X143095Y1036269D02*
X139154D01*
G01X123752Y1044925D02*
X116512Y1085985D01*
G01X125077Y1045474D02*
X117837Y1086534D01*
G01X126500Y1041000D02*
X123752Y1044925D01*
G01X127506Y1042006D02*
X125077Y1045474D01*
G01X131270Y1037660D02*
X126500Y1041000D01*
G01X131819Y1038985D02*
X127506Y1042006D01*
G01X135304Y1036948D02*
X131270Y1037660D01*
G01X139277Y1037669D02*
X131819Y1038985D01*
G01X139154Y1036269D02*
X135304Y1036948D01*
G01X139277Y1037669D02*
X131819Y1038985D01*
G01X143095Y1036269D02*
X139154D01*
G01X143095Y1037669D02*
X139277D01*
G01X130887Y1127419D02*
X122043Y1128978D01*
G01X139611Y1124458D02*
X121494Y1127653D01*
G01X139734Y1125859D02*
X130887Y1127419D01*
G01X139611Y1124458D02*
X121494Y1127653D01*
G01X143095Y1125858D02*
X139734D01*
G01X143095Y1124458D02*
X139611D01*
G01D02*
X121494Y1127653D01*
G01X130887Y1127419D02*
X122043Y1128978D01*
G01X139734Y1125859D02*
X130887Y1127419D01*
G01X143095Y1124458D02*
X139611D01*
G01X143095Y1125858D02*
X139734D01*
G01X139277Y1106961D02*
X132217Y1108206D01*
G01X139154Y1105561D02*
X131668Y1106881D01*
G01X143096Y1106961D02*
X139277D01*
G01X143094Y1105561D02*
X139154D01*
G01D02*
X131668Y1106881D01*
G01X139277Y1106961D02*
X132217Y1108206D01*
G01X143094Y1105561D02*
X139154D01*
G01X143096Y1106961D02*
X139277D01*
G01X128877Y1089994D02*
X114159Y1100300D01*
G01X128328Y1088669D02*
X113153Y1099294D01*
G01X139816Y1088063D02*
X128877Y1089994D01*
G01X139693Y1086663D02*
X128328Y1088669D01*
G01X143096Y1088063D02*
X139816D01*
G01X143094Y1086663D02*
X139693D01*
G01X128328Y1088669D02*
X113153Y1099294D01*
G01X128877Y1089994D02*
X114159Y1100300D01*
G01X139693Y1086663D02*
X128328Y1088669D01*
G01X139816Y1088063D02*
X128877Y1089994D01*
G01X143094Y1086663D02*
X139693D01*
G01X143096Y1088063D02*
X139816D01*
G01X182614Y1203923D02*
X153011Y1209143D01*
G01X182065Y1202598D02*
X153011Y1207721D01*
G01X267367Y1144580D02*
X182614Y1203923D01*
G01X266818Y1143255D02*
X182065Y1202598D01*
G01D02*
X153011Y1207721D01*
G01X182614Y1203923D02*
X153011Y1209143D01*
G01X266818Y1143255D02*
X182065Y1202598D01*
G01X267367Y1144580D02*
X182614Y1203923D01*
G01X180847Y1200567D02*
X153680Y1205358D01*
G01X180298Y1199242D02*
X153680Y1203936D01*
G01X266047Y1140911D02*
X180847Y1200567D01*
G01X265498Y1139586D02*
X180298Y1199242D01*
G01D02*
X153680Y1203936D01*
G01X180847Y1200567D02*
X153680Y1205358D01*
G01X265498Y1139586D02*
X180298Y1199242D01*
G01X266047Y1140911D02*
X180847Y1200567D01*
G01X179448Y1197188D02*
X153846Y1201702D01*
G01X178899Y1195863D02*
X153846Y1200280D01*
G01X264878Y1137373D02*
X179448Y1197188D01*
G01X264329Y1136048D02*
X178899Y1195863D01*
G01D02*
X153846Y1200280D01*
G01X179448Y1197188D02*
X153846Y1201702D01*
G01X264329Y1136048D02*
X178899Y1195863D01*
G01X264878Y1137373D02*
X179448Y1197188D01*
G01X178030Y1193731D02*
X263704Y1133745D01*
G01X177481Y1192406D02*
X263155Y1132420D01*
G01X153766Y1198010D02*
X178030Y1193731D01*
G01X153766Y1196588D02*
X177481Y1192406D01*
G01D02*
X263155Y1132420D01*
G01X178030Y1193731D02*
X263704Y1133745D01*
G01X153766Y1196588D02*
X177481Y1192406D01*
G01X153766Y1198010D02*
X178030Y1193731D01*
G01X118233Y1282746D02*
X125091Y1321638D01*
G01X116908Y1283298D02*
X117247Y1285218D01*
G01X118055Y1282492D02*
X118233Y1282746D01*
G01X112500Y1277000D02*
X116908Y1283295D01*
G01X115851Y1279344D02*
X118055Y1282492D01*
G01X112500Y1277000D02*
X116908Y1283295D01*
G01X113506Y1275994D02*
X115851Y1279344D01*
G01X112500Y1277000D02*
X116908Y1283295D01*
G01X118233Y1282746D02*
X125091Y1321638D01*
G01X118233Y1282746D02*
X125091Y1321638D01*
G01X118233Y1282746D02*
X125091Y1321638D01*
G01X116908Y1283298D02*
X117247Y1285218D01*
G01X118233Y1282746D02*
X125091Y1321638D01*
G01X112500Y1277000D02*
X116908Y1283295D01*
G01X118055Y1282492D02*
X118233Y1282746D01*
G01X115851Y1279344D02*
X118055Y1282492D01*
G01X113506Y1275994D02*
X115851Y1279344D01*
G01X121537Y1341798D02*
X126454Y1369688D01*
G01X120115Y1341798D02*
X125032Y1369688D01*
G01X125091Y1321638D02*
X121537Y1341798D01*
G01X123669Y1321638D02*
X120115Y1341798D01*
G01X119711Y1299193D02*
X123669Y1321638D01*
G01X118777Y1293894D02*
X119115Y1295815D01*
G01X117842Y1288596D02*
X118181Y1290517D01*
G01X120115Y1341798D02*
X125032Y1369688D01*
G01X121537Y1341798D02*
X126454Y1369688D01*
G01X123669Y1321638D02*
X120115Y1341798D01*
G01X125091Y1321638D02*
X121537Y1341798D01*
G01X119711Y1299193D02*
X123669Y1321638D01*
G01X118777Y1293894D02*
X119115Y1295815D01*
G01X117842Y1288596D02*
X118181Y1290517D01*
G01X116208Y1342332D02*
X121046Y1369767D01*
G01X120006Y1355807D02*
X122425Y1369524D01*
G01X116208Y1342332D02*
X121046Y1369767D01*
G01X117630Y1342332D02*
X120006Y1355807D01*
G01X116208Y1342332D02*
X121046Y1369767D01*
G01X120752Y1324628D02*
X117630Y1342332D01*
G01X119330Y1324628D02*
X116208Y1342332D01*
G01X115958Y1297497D02*
X120752Y1324628D01*
G01X117399Y1313703D02*
X119330Y1324628D01*
G01X116477Y1308484D02*
X116816Y1310404D01*
G01X115555Y1303265D02*
X115894Y1305185D01*
G01X114633Y1298046D02*
X114972Y1299966D01*
G01X113506Y1293994D02*
X115958Y1297497D01*
G01X112500Y1295000D02*
X114633Y1298046D01*
G01X116208Y1342332D02*
X121046Y1369767D01*
G01X120006Y1355807D02*
X122425Y1369524D01*
G01X117630Y1342332D02*
X120006Y1355807D01*
G01X119330Y1324628D02*
X116208Y1342332D01*
G01X120752Y1324628D02*
X117630Y1342332D01*
G01X117399Y1313703D02*
X119330Y1324628D01*
G01X115958Y1297497D02*
X120752Y1324628D01*
G01X116477Y1308484D02*
X116816Y1310404D01*
G01X115958Y1297497D02*
X120752Y1324628D01*
G01X115555Y1303265D02*
X115894Y1305185D01*
G01X115958Y1297497D02*
X120752Y1324628D01*
G01X114633Y1298046D02*
X114972Y1299966D01*
G01X115958Y1297497D02*
X120752Y1324628D01*
G01X112500Y1295000D02*
X114633Y1298046D01*
G01X113506Y1293994D02*
X115958Y1297497D01*
G01X113778Y1341298D02*
X118707Y1369265D01*
G01X112356Y1341298D02*
X117285Y1369265D01*
G01X116610Y1325237D02*
X113778Y1341298D01*
G01X115188Y1325237D02*
X112356Y1341298D01*
G01X114938Y1315754D02*
X116610Y1325237D01*
G01X114849Y1323317D02*
X115188Y1325237D01*
G01X113613Y1316303D02*
X114254Y1319939D01*
G01X113006Y1312994D02*
X114938Y1315754D01*
G01X112000Y1314000D02*
X113613Y1316303D01*
G01X112356Y1341298D02*
X117285Y1369265D01*
G01X113778Y1341298D02*
X118707Y1369265D01*
G01X115188Y1325237D02*
X112356Y1341298D01*
G01X116610Y1325237D02*
X113778Y1341298D01*
G01X114849Y1323317D02*
X115188Y1325237D01*
G01X114938Y1315754D02*
X116610Y1325237D01*
G01X113613Y1316303D02*
X114254Y1319939D01*
G01X114938Y1315754D02*
X116610Y1325237D01*
G01X112000Y1314000D02*
X113613Y1316303D01*
G01X113006Y1312994D02*
X114938Y1315754D01*
G01X124034Y1383406D02*
X121597Y1386892D01*
G01X122709Y1382857D02*
X120589Y1385887D01*
G01X126454Y1369688D02*
X124035Y1383406D01*
G01X125032Y1369688D02*
X122709Y1382857D01*
G01D02*
X120589Y1385887D01*
G01X124034Y1383406D02*
X121597Y1386892D01*
G01X125032Y1369688D02*
X122709Y1382857D01*
G01X126454Y1369688D02*
X124035Y1383406D01*
G01X120459Y1381157D02*
X118427Y1384060D01*
G01X119134Y1380608D02*
X117421Y1383054D01*
G01X122468Y1369767D02*
X120459Y1381157D01*
G01X121046Y1369767D02*
X119134Y1380608D01*
G01X122425Y1369523D02*
X122468Y1369767D01*
G01X119134Y1380608D02*
X117421Y1383054D01*
G01X120459Y1381157D02*
X118427Y1384060D01*
G01X121046Y1369767D02*
X119134Y1380608D01*
G01X122468Y1369767D02*
X120459Y1381157D01*
G01X122425Y1369523D02*
X122468Y1369767D01*
G01X116998Y1378959D02*
X115071Y1381712D01*
G01X115673Y1378410D02*
X114065Y1380706D01*
G01X118707Y1369265D02*
X116998Y1378959D01*
G01X117285Y1369265D02*
X115673Y1378410D01*
G01D02*
X114065Y1380706D01*
G01X116998Y1378959D02*
X115071Y1381712D01*
G01X117285Y1369265D02*
X115673Y1378410D01*
G01X118707Y1369265D02*
X116998Y1378959D01*
G01X143096Y1493575D02*
X139693D01*
G01X143094Y1492175D02*
X139570D01*
G01X143094D02*
X139570D01*
G01X143096Y1493575D02*
X139693D01*
G01X143095Y1443181D02*
X139031D01*
G01X143095Y1441781D02*
X139154D01*
G01X143095D02*
X139154D01*
G01X143095Y1443181D02*
X139031D01*
G01X143095Y1531370D02*
X139365D01*
G01X143095Y1529970D02*
X139488D01*
G01X143095D02*
X139488D01*
G01X143095Y1531370D02*
X139365D01*
G01X134202Y1511622D02*
X126593Y1512964D01*
G01X134202Y1510200D02*
X126593Y1511542D01*
G01X139031Y1512473D02*
X134202Y1511622D01*
G01X139154Y1511073D02*
X134202Y1510200D01*
G01X143096Y1512473D02*
X139031D01*
G01X143094Y1511073D02*
X139154D01*
G01X134202Y1510200D02*
X126593Y1511542D01*
G01X134202Y1511622D02*
X126593Y1512964D01*
G01X139154Y1511073D02*
X134202Y1510200D01*
G01X139031Y1512473D02*
X134202Y1511622D01*
G01X143094Y1511073D02*
X139154D01*
G01X143096Y1512473D02*
X139031D01*
G01X157456Y1624069D02*
G02X156636Y1623729I-1177J1679D01*
G01X156653Y1625216D02*
G02X156393Y1625108I-373J532D01*
G01X159761Y1625682D02*
X157456Y1624069D01*
G01X161263Y1628443D02*
X156653Y1625216D01*
G01X162066Y1627296D02*
X159761Y1625682D01*
G01X161263Y1628443D02*
X156653Y1625216D01*
G01X162569Y1627799D02*
G02X162066Y1627296I-1679J1176D01*
G01X161422Y1628602D02*
G02X161263Y1628443I-532J373D01*
G01X164519Y1630587D02*
X162569Y1627799D01*
G01X163372Y1631390D02*
X161422Y1628602D01*
G01X165148Y1632104D02*
G02X164519Y1630587I-3742J663D01*
G01X163769Y1632348D02*
G02X163372Y1631390I-2363J418D01*
G01X165569Y1634490D02*
X165148Y1632104D01*
G01X164190Y1634732D02*
X163769Y1632348D01*
G01X165568Y1635810D02*
G02X165569Y1634490I-3742J-663D01*
G01X164189Y1635566D02*
G02X164190Y1634732I-2363J-420D01*
G01X163501Y1647532D02*
X165568Y1635810D01*
G01X163850Y1637486D02*
X164189Y1635566D01*
G01X162929Y1642706D02*
X163268Y1640785D01*
G01X163273Y1648817D02*
X163500Y1647532D01*
G01X161894Y1648574D02*
X162347Y1646005D01*
G01X156653Y1625216D02*
G02X156393Y1625108I-373J532D01*
G01X157456Y1624069D02*
G02X156636Y1623729I-1177J1679D01*
G01X161263Y1628443D02*
X156653Y1625216D01*
G01X159761Y1625682D02*
X157456Y1624069D01*
G01X162066Y1627296D02*
X159761Y1625682D01*
G01X161422Y1628602D02*
G02X161263Y1628443I-532J373D01*
G01X162569Y1627799D02*
G02X162066Y1627296I-1679J1176D01*
G01X163372Y1631390D02*
X161422Y1628602D01*
G01X164519Y1630587D02*
X162569Y1627799D01*
G01X163769Y1632348D02*
G02X163372Y1631390I-2363J418D01*
G01X165148Y1632104D02*
G02X164519Y1630587I-3742J663D01*
G01X164190Y1634732D02*
X163769Y1632348D01*
G01X165569Y1634490D02*
X165148Y1632104D01*
G01X164189Y1635566D02*
G02X164190Y1634732I-2363J-420D01*
G01X165568Y1635810D02*
G02X165569Y1634490I-3742J-663D01*
G01X163850Y1637486D02*
X164189Y1635566D01*
G01X163501Y1647532D02*
X165568Y1635810D01*
G01X162929Y1642706D02*
X163268Y1640785D01*
G01X163501Y1647532D02*
X165568Y1635810D01*
G01X161894Y1648574D02*
X162347Y1646005D01*
G01X163273Y1648817D02*
X163500Y1647532D01*
G01X159410Y1620667D02*
G02X158590Y1620327I-1177J1679D01*
G01X158347Y1621706D02*
G03X158607Y1621814I-113J640D01*
G01X164304Y1624093D02*
X159410Y1620667D01*
G01X158607Y1621814D02*
X163501Y1625240D01*
G01X164807Y1624596D02*
G02X164304Y1624093I-1679J1176D01*
G01X163501Y1625240D02*
G03X163660Y1625399I-373J532D01*
G01X168516Y1629892D02*
X164807Y1624596D01*
G01X163660Y1625399D02*
X167369Y1630695D01*
G01X168856Y1630712D02*
G02X168516Y1629892I-2019J357D01*
G01X167369Y1630695D02*
G03X167477Y1630955I-532J374D01*
G01X169525Y1634509D02*
X168856Y1630712D01*
G01X167477Y1630955D02*
X168146Y1634752D01*
G01X169525Y1635221D02*
G02Y1634509I-2019J-356D01*
G01X168146Y1634752D02*
G03Y1634978I-640J113D01*
G01X166707Y1651199D02*
X169525Y1635221D01*
G01X168146Y1634978D02*
X165328Y1650955D01*
G01X168146Y1634978D02*
X165328Y1650955D01*
G01X166707Y1651199D02*
X169525Y1635221D01*
G01X168146Y1634752D02*
G03Y1634978I-640J113D01*
G01X169525Y1635221D02*
G02Y1634509I-2019J-356D01*
G01X167477Y1630955D02*
X168146Y1634752D01*
G01X169525Y1634509D02*
X168856Y1630712D01*
G01X167369Y1630695D02*
G03X167477Y1630955I-532J374D01*
G01X168856Y1630712D02*
G02X168516Y1629892I-2019J357D01*
G01X163660Y1625399D02*
X167369Y1630695D01*
G01X168516Y1629892D02*
X164807Y1624596D01*
G01X163501Y1625240D02*
G03X163660Y1625399I-373J532D01*
G01X164807Y1624596D02*
G02X164304Y1624093I-1679J1176D01*
G01X158607Y1621814D02*
X163501Y1625240D01*
G01X164304Y1624093D02*
X159410Y1620667D01*
G01X158347Y1621706D02*
G03X158607Y1621814I-113J640D01*
G01X159410Y1620667D02*
G02X158590Y1620327I-1177J1679D01*
G01X174769Y1634004D02*
X171344Y1653430D01*
G01X173390Y1633761D02*
X169965Y1653187D01*
G01X174769Y1633292D02*
G03Y1634004I-2019J356D01*
G01X173390Y1633535D02*
G03Y1633761I-640J113D01*
G01X174028Y1629089D02*
X174769Y1633292D01*
G01X172649Y1629332D02*
X173390Y1633535D01*
G01X173688Y1628269D02*
G03X174028Y1629089I-1679J1177D01*
G01X172541Y1629073D02*
G03X172649Y1629332I-532J374D01*
G01X167788Y1619843D02*
X173688Y1628269D01*
G01X166641Y1620646D02*
X172541Y1629072D01*
G01X167285Y1619340D02*
G03X167788Y1619843I-1176J1679D01*
G01X166482Y1620487D02*
G03X166641Y1620646I-373J532D01*
G01X163214Y1616489D02*
X167285Y1619340D01*
G01X162411Y1617636D02*
X166482Y1620487D01*
G01X162394Y1616149D02*
G03X163214Y1616489I-357J2019D01*
G01X162151Y1617528D02*
G03X162411Y1617636I-114J640D01*
G01X173390Y1633761D02*
X169965Y1653187D01*
G01X174769Y1634004D02*
X171344Y1653430D01*
G01X173390Y1633535D02*
G03Y1633761I-640J113D01*
G01X174769Y1633292D02*
G03Y1634004I-2019J356D01*
G01X172649Y1629332D02*
X173390Y1633535D01*
G01X174028Y1629089D02*
X174769Y1633292D01*
G01X172541Y1629073D02*
G03X172649Y1629332I-532J374D01*
G01X173688Y1628269D02*
G03X174028Y1629089I-1679J1177D01*
G01X166641Y1620646D02*
X172541Y1629072D01*
G01X167788Y1619843D02*
X173688Y1628269D01*
G01X166482Y1620487D02*
G03X166641Y1620646I-373J532D01*
G01X167285Y1619340D02*
G03X167788Y1619843I-1176J1679D01*
G01X162411Y1617636D02*
X166482Y1620487D01*
G01X163214Y1616489D02*
X167285Y1619340D01*
G01X162151Y1617528D02*
G03X162411Y1617636I-114J640D01*
G01X162394Y1616149D02*
G03X163214Y1616489I-357J2019D01*
G01X164829Y1613100D02*
G02X164010Y1612760I-1177J1678D01*
G01X163766Y1614139D02*
G03X164025Y1614247I-114J639D01*
G01X169669Y1616489D02*
X164829Y1613100D01*
G01X164026Y1614247D02*
X168866Y1617636D01*
G01X164025Y1614247D02*
X164026D01*
G01X170172Y1616992D02*
G02X169669Y1616489I-1679J1176D01*
G01X168866Y1617636D02*
G03X169025Y1617795I-373J532D01*
G01X177206Y1627038D02*
X170172Y1616992D01*
G01X169025Y1617795D02*
X176059Y1627841D01*
G01X177546Y1627858D02*
G02X177206Y1627038I-2019J357D01*
G01X176059Y1627842D02*
G03X176167Y1628101I-531J374D01*
G01X178456Y1633020D02*
X177546Y1627858D01*
G01X176167Y1628101D02*
X177077Y1633263D01*
G01X178456Y1633732D02*
G02Y1633020I-2019J-356D01*
G01X177077Y1633263D02*
G03Y1633489I-640J113D01*
G01X174698Y1655048D02*
X178456Y1633732D01*
G01X177077Y1633489D02*
X173319Y1654804D01*
G01X177077Y1633489D02*
X173319Y1654804D01*
G01X174698Y1655048D02*
X178456Y1633732D01*
G01X177077Y1633263D02*
G03Y1633489I-640J113D01*
G01X178456Y1633732D02*
G02Y1633020I-2019J-356D01*
G01X176167Y1628101D02*
X177077Y1633263D01*
G01X178456Y1633020D02*
X177546Y1627858D01*
G01X176059Y1627842D02*
G03X176167Y1628101I-531J374D01*
G01X177546Y1627858D02*
G02X177206Y1627038I-2019J357D01*
G01X169025Y1617795D02*
X176059Y1627841D01*
G01X177206Y1627038D02*
X170172Y1616992D01*
G01X168866Y1617636D02*
G03X169025Y1617795I-373J532D01*
G01X170172Y1616992D02*
G02X169669Y1616489I-1679J1176D01*
G01X164026Y1614247D02*
X168866Y1617636D01*
G01X169669Y1616489D02*
X164829Y1613100D01*
G01X164025Y1614247D02*
X164026D01*
G01X169669Y1616489D02*
X164829Y1613100D01*
G01X163766Y1614139D02*
G03X164025Y1614247I-114J639D01*
G01X164829Y1613100D02*
G02X164010Y1612760I-1177J1678D01*
G01X177769Y1610773D02*
X747524Y1510331D01*
G01X177526Y1609394D02*
X747279Y1508951D01*
G01X176414Y1610773D02*
G02X177769I677J-3841D01*
G01X176657Y1609394D02*
G02X177526I435J-2462D01*
G01D02*
X747279Y1508951D01*
G01X177769Y1610773D02*
X747524Y1510331D01*
G01X176657Y1609394D02*
G02X177526I435J-2462D01*
G01X176414Y1610773D02*
G02X177769I677J-3841D01*
G01X177756Y1607006D02*
G03X176402I-677J-3841D01*
G01X177513Y1605626D02*
G03X176645I-434J-2462D01*
G01X790051Y1499036D02*
X177756Y1607005D01*
G01X789808Y1497657D02*
X177513Y1605626D01*
G01D02*
G03X176645I-434J-2462D01*
G01X177756Y1607006D02*
G03X176402I-677J-3841D01*
G01X789808Y1497657D02*
X177513Y1605626D01*
G01X790051Y1499036D02*
X177756Y1607005D01*
G01X178126Y1603216D02*
G03X177293I-416J-2363D01*
G01X177884Y1601837D02*
G03X177536I-174J-985D01*
G01X833778Y1487602D02*
X178126Y1603216D01*
G01X177883Y1601837D02*
X177884D01*
G01X833778Y1486180D02*
X177883Y1601837D01*
G01X177884D02*
G03X177536I-174J-985D01*
G01X178126Y1603216D02*
G03X177293I-416J-2363D01*
G01X177883Y1601837D02*
X177884D01*
G01X833778Y1487602D02*
X178126Y1603216D01*
G01X833778Y1486180D02*
X177883Y1601837D01*
G01X833778Y1487602D02*
X178126Y1603216D01*
G01X178289Y1599379D02*
G03X176935I-677J-3841D01*
G01X178046Y1597999D02*
G03X177178I-434J-2462D01*
G01X800466Y1489673D02*
X178289Y1599379D01*
G01X800222Y1488294D02*
X178046Y1597999D01*
G01D02*
G03X177178I-434J-2462D01*
G01X178289Y1599379D02*
G03X176935I-677J-3841D01*
G01X800222Y1488294D02*
X178046Y1597999D01*
G01X800466Y1489673D02*
X178289Y1599379D01*
G01X162644Y1650337D02*
G02X163273Y1648817I-3114J-2179D01*
G01X161497Y1649534D02*
G02X161894Y1648574I-1967J-1375D01*
G01X158992Y1655555D02*
X162644Y1650337D01*
G01X157845Y1654752D02*
X161497Y1649534D01*
G01X158058Y1656489D02*
G02X158992Y1655555I-2179J-3113D01*
G01X157255Y1655342D02*
G02X157845Y1654752I-1376J-1966D01*
G01X154346Y1659088D02*
X158058Y1656489D01*
G01X153543Y1657941D02*
X157255Y1655342D01*
G01X153483Y1659467D02*
G02X154346Y1659088I-515J-2344D01*
G01X153183Y1658099D02*
G02X153543Y1657941I-214J-977D01*
G01X127943Y1665063D02*
X153483Y1659467D01*
G01X151278Y1658516D02*
X153183Y1658099D01*
G01X146101Y1659650D02*
X148006Y1659233D01*
G01X140924Y1660784D02*
X142829Y1660367D01*
G01X127643Y1663695D02*
X137652Y1661501D01*
G01X127642Y1663695D02*
X127643D01*
G01X127180Y1665376D02*
G03X127943Y1665063I1279J2031D01*
G01X126434Y1664190D02*
G03X127642Y1663695I2024J3217D01*
G01X124783Y1665228D02*
X126434Y1664190D01*
G01X120295Y1668048D02*
X121946Y1667010D01*
G01X117458Y1669830D02*
X117459D01*
G01X161497Y1649534D02*
G02X161894Y1648574I-1967J-1375D01*
G01X162644Y1650337D02*
G02X163273Y1648817I-3114J-2179D01*
G01X157845Y1654752D02*
X161497Y1649534D01*
G01X158992Y1655555D02*
X162644Y1650337D01*
G01X157255Y1655342D02*
G02X157845Y1654752I-1376J-1966D01*
G01X158058Y1656489D02*
G02X158992Y1655555I-2179J-3113D01*
G01X153543Y1657941D02*
X157255Y1655342D01*
G01X154346Y1659088D02*
X158058Y1656489D01*
G01X153183Y1658099D02*
G02X153543Y1657941I-214J-977D01*
G01X153483Y1659467D02*
G02X154346Y1659088I-515J-2344D01*
G01X151278Y1658516D02*
X153183Y1658099D01*
G01X127943Y1665063D02*
X153483Y1659467D01*
G01X146101Y1659650D02*
X148006Y1659233D01*
G01X127943Y1665063D02*
X153483Y1659467D01*
G01X140924Y1660784D02*
X142829Y1660367D01*
G01X127943Y1665063D02*
X153483Y1659467D01*
G01X127643Y1663695D02*
X137652Y1661501D01*
G01X127943Y1665063D02*
X153483Y1659467D01*
G01X127642Y1663695D02*
X127643D01*
G01X127943Y1665063D02*
X153483Y1659467D01*
G01X126434Y1664190D02*
G03X127642Y1663695I2024J3217D01*
G01X127180Y1665376D02*
G03X127943Y1665063I1279J2031D01*
G01X124783Y1665228D02*
X126434Y1664190D01*
G01X120295Y1668048D02*
X121946Y1667010D01*
G01X117458Y1669830D02*
X117459D01*
G01X166367Y1652018D02*
G02X166707Y1651199I-1679J-1177D01*
G01X165328Y1650955D02*
G03X165220Y1651215I-640J-113D01*
G01X159574Y1661721D02*
X166367Y1652018D01*
G01X165220Y1651215D02*
X158427Y1660918D01*
G01X158985Y1662311D02*
G02X159574Y1661721I-1378J-1965D01*
G01X158427Y1660918D02*
G03X158181Y1661164I-819J-573D01*
G01X113996Y1692103D02*
X113021Y1691931D01*
G01X115593Y1690984D02*
X113996Y1692103D01*
G01X118337Y1689063D02*
X117362Y1688891D01*
G01X119934Y1687944D02*
X118337Y1689063D01*
G01X122678Y1686023D02*
X121704Y1685851D01*
G01X132812Y1678927D02*
X122678Y1686023D01*
G01X132813Y1678927D02*
X132812D01*
G01X135623Y1676960D02*
X134592Y1676778D01*
G01X137220Y1675841D02*
X135623Y1676960D01*
G01X140030Y1673874D02*
X138999Y1673692D01*
G01X149366Y1667336D02*
X140030Y1673874D01*
G01X149367Y1667336D02*
X149366D01*
G01X152177Y1665368D02*
X151146Y1665187D01*
G01X153774Y1664250D02*
X152177Y1665368D01*
G01X156584Y1662283D02*
X155553Y1662101D01*
G01X158181Y1661164D02*
X156584Y1662283D01*
G01X113996Y1692103D02*
X113021Y1691931D01*
G01X115593Y1690984D02*
X113996Y1692103D01*
G01X118337Y1689063D02*
X117362Y1688891D01*
G01X119934Y1687944D02*
X118337Y1689063D01*
G01X122678Y1686023D02*
X121704Y1685851D01*
G01X132812Y1678927D02*
X122678Y1686023D01*
G01X132813Y1678927D02*
X132812D01*
G01X135623Y1676960D02*
X134592Y1676778D01*
G01X137220Y1675841D02*
X135623Y1676960D01*
G01X140030Y1673874D02*
X138999Y1673692D01*
G01X149366Y1667336D02*
X140030Y1673874D01*
G01X149367Y1667336D02*
X149366D01*
G01X152177Y1665368D02*
X151146Y1665187D01*
G01X153774Y1664250D02*
X152177Y1665368D01*
G01X156584Y1662283D02*
X155553Y1662101D01*
G01X158181Y1661164D02*
X156584Y1662283D01*
G01X158427Y1660918D02*
G03X158181Y1661164I-819J-573D01*
G01X158985Y1662311D02*
G02X159574Y1661721I-1378J-1965D01*
G01X165220Y1651215D02*
X158427Y1660918D01*
G01X159574Y1661721D02*
X166367Y1652018D01*
G01X165328Y1650955D02*
G03X165220Y1651215I-640J-113D01*
G01X166367Y1652018D02*
G02X166707Y1651199I-1679J-1177D01*
G01X114408Y1711014D02*
X113377Y1710832D01*
G01X116005Y1709896D02*
X114408Y1711014D01*
G01X118815Y1707928D02*
X117784Y1707747D01*
G01X120412Y1706810D02*
X118815Y1707928D01*
G01X123222Y1704842D02*
X122094Y1704644D01*
G01X130838Y1699510D02*
X123222Y1704842D01*
G01X133648Y1697542D02*
X132617Y1697360D01*
G01X135245Y1696424D02*
X133648Y1697542D01*
G01X138055Y1694456D02*
X137024Y1694275D01*
G01X139652Y1693338D02*
X138055Y1694456D01*
G01X142462Y1691370D02*
X141431Y1691189D01*
G01X144059Y1690252D02*
X142462Y1691370D01*
G01X145452Y1690810D02*
G03X144862Y1691400I-1966J-1376D01*
G01X144304Y1690007D02*
G03X144059Y1690252I-819J-574D01*
G01X170947Y1654390D02*
X145452Y1690810D01*
G01X145422Y1688410D02*
X144304Y1690007D01*
G01X169800Y1653587D02*
X147389Y1685600D01*
G01X171344Y1653430D02*
G03X170947Y1654390I-2364J-415D01*
G01X169965Y1653187D02*
G03X169800Y1653587I-985J-172D01*
G01X114408Y1711014D02*
X113377Y1710832D01*
G01X116005Y1709896D02*
X114408Y1711014D01*
G01X118815Y1707928D02*
X117784Y1707747D01*
G01X120412Y1706810D02*
X118815Y1707928D01*
G01X123222Y1704842D02*
X122094Y1704644D01*
G01X130838Y1699510D02*
X123222Y1704842D01*
G01X133648Y1697542D02*
X132617Y1697360D01*
G01X135245Y1696424D02*
X133648Y1697542D01*
G01X138055Y1694456D02*
X137024Y1694275D01*
G01X139652Y1693338D02*
X138055Y1694456D01*
G01X142462Y1691370D02*
X141431Y1691189D01*
G01X144059Y1690252D02*
X142462Y1691370D01*
G01X144304Y1690007D02*
G03X144059Y1690252I-819J-574D01*
G01X145452Y1690810D02*
G03X144862Y1691400I-1966J-1376D01*
G01X145422Y1688410D02*
X144304Y1690007D01*
G01X170947Y1654390D02*
X145452Y1690810D01*
G01X169800Y1653587D02*
X147389Y1685600D01*
G01X170947Y1654390D02*
X145452Y1690810D01*
G01X169965Y1653187D02*
G03X169800Y1653587I-985J-172D01*
G01X171344Y1653430D02*
G03X170947Y1654390I-2364J-415D01*
G01X174302Y1656006D02*
G02X174698Y1655048I-1968J-1374D01*
G01X173319Y1654804D02*
G03X173154Y1655203I-985J-174D01*
G01X119490Y1734465D02*
X174302Y1656006D01*
G01X130120Y1716800D02*
X129003Y1718399D01*
G01X173154Y1655204D02*
X132038Y1714054D01*
G01X119490Y1734465D02*
X174302Y1656006D01*
G01X119490Y1734465D02*
X174302Y1656006D01*
G01X119490Y1734465D02*
X174302Y1656006D01*
G01X130120Y1716800D02*
X129003Y1718399D01*
G01X119490Y1734465D02*
X174302Y1656006D01*
G01X173154Y1655204D02*
X132038Y1714054D01*
G01X119490Y1734465D02*
X174302Y1656006D01*
G01X173319Y1654804D02*
G03X173154Y1655203I-985J-174D01*
G01X174302Y1656006D02*
G02X174698Y1655048I-1968J-1374D01*
G01X146033Y1759814D02*
G02X145419Y1760428I1434J2048D01*
G01X145229Y1758667D02*
G02X144271Y1759624I2236J3196D01*
G01X159409Y1750450D02*
X146033Y1759814D01*
G01X145230Y1758667D02*
X145229D01*
G01X158860Y1749125D02*
X145230Y1758667D01*
G01X164815Y1749496D02*
X159409Y1750450D01*
G01X164814Y1748073D02*
X158862Y1749124D01*
G01X742742Y1851449D02*
X164815Y1749496D01*
G01X743292Y1850124D02*
X164814Y1748073D01*
G01X145229Y1758667D02*
G02X144271Y1759624I2236J3196D01*
G01X146033Y1759814D02*
G02X145419Y1760428I1434J2048D01*
G01X145230Y1758667D02*
X145229D01*
G01X159409Y1750450D02*
X146033Y1759814D01*
G01X158860Y1749125D02*
X145230Y1758667D01*
G01X159409Y1750450D02*
X146033Y1759814D01*
G01X164814Y1748073D02*
X158862Y1749124D01*
G01X164815Y1749496D02*
X159409Y1750450D01*
G01X743292Y1850124D02*
X164814Y1748073D01*
G01X742742Y1851449D02*
X164815Y1749496D01*
G01X164751Y1745615D02*
X768671Y1852133D01*
G01X164751Y1744193D02*
X769220Y1850808D01*
G01X158271Y1746758D02*
X164751Y1745615D01*
G01X157723Y1745432D02*
X164751Y1744193D01*
G01X143297Y1757243D02*
X158271Y1746758D01*
G01X142493Y1756095D02*
X157723Y1745432D01*
G01X143294Y1757245D02*
X143297Y1757243D01*
G01X142493Y1756095D02*
X157723Y1745432D01*
G01X142680Y1757859D02*
G03X143294Y1757245I2048J1434D01*
G01X141536Y1757052D02*
G03X142493Y1756095I3194J2237D01*
G01X119243Y1791314D02*
X142680Y1757860D01*
G01X118169Y1790405D02*
X141533Y1757056D01*
G01X118835Y1791715D02*
X119243Y1791314D01*
G01X117936Y1790634D02*
X118169Y1790405D01*
G01X164751Y1744193D02*
X769220Y1850808D01*
G01X164751Y1745615D02*
X768671Y1852133D01*
G01X157723Y1745432D02*
X164751Y1744193D01*
G01X158271Y1746758D02*
X164751Y1745615D01*
G01X142493Y1756095D02*
X157723Y1745432D01*
G01X143297Y1757243D02*
X158271Y1746758D01*
G01X143294Y1757245D02*
X143297Y1757243D01*
G01X141536Y1757052D02*
G03X142493Y1756095I3194J2237D01*
G01X142680Y1757859D02*
G03X143294Y1757245I2048J1434D01*
G01X118169Y1790405D02*
X141533Y1757056D01*
G01X119243Y1791314D02*
X142680Y1757860D01*
G01X117936Y1790634D02*
X118169Y1790405D01*
G01X118835Y1791715D02*
X119243Y1791314D01*
G01X119852Y1783894D02*
G03X118894Y1784852I-3195J-2237D01*
G01X118705Y1783091D02*
G03X118091Y1783705I-2048J-1434D01*
G01X140251Y1754767D02*
X119852Y1783894D01*
G01X139104Y1753964D02*
X118705Y1783091D01*
G01X140865Y1754153D02*
G02X140251Y1754767I1434J2048D01*
G01X140062Y1753006D02*
G02X139104Y1753964I2237J3195D01*
G01X156641Y1743110D02*
X140865Y1754153D01*
G01X156092Y1741785D02*
X140062Y1753006D01*
G01X164817Y1741668D02*
X156641Y1743110D01*
G01X164817Y1740246D02*
X156092Y1741785D01*
G01X795112Y1852817D02*
X164817Y1741668D01*
G01X795661Y1851492D02*
X164817Y1740246D01*
G01X118705Y1783091D02*
G03X118091Y1783705I-2048J-1434D01*
G01X119852Y1783894D02*
G03X118894Y1784852I-3195J-2237D01*
G01X139104Y1753964D02*
X118705Y1783091D01*
G01X140251Y1754767D02*
X119852Y1783894D01*
G01X140062Y1753006D02*
G02X139104Y1753964I2237J3195D01*
G01X140865Y1754153D02*
G02X140251Y1754767I1434J2048D01*
G01X156092Y1741785D02*
X140062Y1753006D01*
G01X156641Y1743110D02*
X140865Y1754153D01*
G01X164817Y1740246D02*
X156092Y1741785D01*
G01X164817Y1741668D02*
X156641Y1743110D01*
G01X795661Y1851492D02*
X164817Y1740246D01*
G01X795112Y1852817D02*
X164817Y1741668D01*
G01X121015Y1729836D02*
X118357Y1733640D01*
G01X124050Y1725490D02*
X122933Y1727089D01*
G01X127085Y1721145D02*
X125968Y1722744D01*
G01X119325Y1734864D02*
G03X119490Y1734465I985J174D01*
G01X118346Y1733641D02*
G02X117950Y1734599I1968J1374D01*
G01X115816Y1754773D02*
X119325Y1734864D01*
G01X115313Y1749560D02*
X114974Y1751481D01*
G01X116247Y1744262D02*
X115908Y1746182D01*
G01X117950Y1734599D02*
X116842Y1740884D01*
G01X115457Y1756809D02*
X115812Y1754796D01*
G01X114379Y1754859D02*
X114078Y1756566D01*
G01X115252Y1757514D02*
G02X115457Y1756809I-3135J-1294D01*
G01X113958Y1756979D02*
G03X113751Y1757356I-1831J-760D01*
G01X114078Y1756566D02*
G03X113958Y1756979I-1961J-346D01*
G01X114898Y1758159D02*
G02X115252Y1757514I-2771J-1940D01*
G01X113958Y1756979D02*
G03X113751Y1757356I-1831J-760D01*
G01X114078Y1756566D02*
G03X113958Y1756979I-1961J-346D01*
G01X111593Y1762878D02*
X114898Y1758159D01*
G01X111593Y1762878D02*
X114898Y1758159D01*
G01X113958Y1756979D02*
G03X113751Y1757356I-1831J-760D01*
G01X115252Y1757514D02*
G02X115457Y1756809I-3135J-1294D01*
G01X114898Y1758159D02*
G02X115252Y1757514I-2771J-1940D01*
G01X114078Y1756566D02*
G03X113958Y1756979I-1961J-346D01*
G01X115252Y1757514D02*
G02X115457Y1756809I-3135J-1294D01*
G01X114898Y1758159D02*
G02X115252Y1757514I-2771J-1940D01*
G01X114379Y1754859D02*
X114078Y1756566D01*
G01X115457Y1756809D02*
X115812Y1754796D01*
G01X115313Y1749560D02*
X114974Y1751481D01*
G01X115816Y1754773D02*
X119325Y1734864D01*
G01X116247Y1744262D02*
X115908Y1746182D01*
G01X115816Y1754773D02*
X119325Y1734864D01*
G01X117950Y1734599D02*
X116842Y1740884D01*
G01X115816Y1754773D02*
X119325Y1734864D01*
G01X118346Y1733641D02*
G02X117950Y1734599I1968J1374D01*
G01X119325Y1734864D02*
G03X119490Y1734465I985J174D01*
G01X121015Y1729836D02*
X118357Y1733640D01*
G01X124050Y1725490D02*
X122933Y1727089D01*
G01X127085Y1721145D02*
X125968Y1722744D01*
G01X117572Y1780781D02*
G03X116983Y1781370I-1966J-1377D01*
G01X116424Y1779978D02*
G03X116178Y1780224I-819J-573D01*
G01X137871Y1751787D02*
X117572Y1780781D01*
G01X136724Y1750983D02*
X116424Y1779978D01*
G01X138484Y1751173D02*
G02X137871Y1751787I1436J2047D01*
G01X137681Y1750026D02*
G02X136724Y1750983I2237J3194D01*
G01X155986Y1738917D02*
X138484Y1751173D01*
G01X155438Y1737591D02*
X137681Y1750026D01*
G01X164112Y1737483D02*
X155986Y1738917D01*
G01X164112Y1736061D02*
X155438Y1737591D01*
G01X830708Y1855269D02*
X164112Y1737483D01*
G01X830709Y1853847D02*
X164112Y1736061D01*
G01X116424Y1779978D02*
G03X116178Y1780224I-819J-573D01*
G01X117572Y1780781D02*
G03X116983Y1781370I-1966J-1377D01*
G01X136724Y1750983D02*
X116424Y1779978D01*
G01X137871Y1751787D02*
X117572Y1780781D01*
G01X137681Y1750026D02*
G02X136724Y1750983I2237J3194D01*
G01X138484Y1751173D02*
G02X137871Y1751787I1436J2047D01*
G01X155438Y1737591D02*
X137681Y1750026D01*
G01X155986Y1738917D02*
X138484Y1751173D01*
G01X164112Y1736061D02*
X155438Y1737591D01*
G01X164112Y1737483D02*
X155986Y1738917D01*
G01X830709Y1853847D02*
X164112Y1736061D01*
G01X830708Y1855269D02*
X164112Y1737483D01*
G01X143095Y1847293D02*
X139154D01*
G01X143095Y1848693D02*
X139031D01*
G01X143095D02*
X139031D01*
G01X143095Y1847293D02*
X139154D01*
G01X139488Y1935482D02*
X111769Y1930594D01*
G01X143095Y1935482D02*
X139488D01*
G01X143095Y1936882D02*
X139365D01*
G01X139488Y1935482D02*
X111769Y1930594D01*
G01X143095Y1936882D02*
X139365D01*
G01X143095Y1935482D02*
X139488D01*
G01X143094Y1916585D02*
X139154D01*
G01X143096Y1917985D02*
X139031D01*
G01X143096D02*
X139031D01*
G01X143094Y1916585D02*
X139154D01*
G01X143094Y1897687D02*
X139693D01*
G01X143096Y1899087D02*
X139570D01*
G01X143096D02*
X139570D01*
G01X143094Y1897687D02*
X139693D01*
G01X226722Y843949D02*
X329055Y772292D01*
G01X225716Y842943D02*
X328506Y770967D01*
G01X225716Y842943D02*
X328506Y770967D01*
G01X226722Y843949D02*
X329055Y772292D01*
G01X324166Y769462D02*
X220992Y841708D01*
G01X323617Y768137D02*
X219986Y840702D01*
G01X323617Y768137D02*
X219986Y840702D01*
G01X324166Y769462D02*
X220992Y841708D01*
G01X218421Y839072D02*
X322968Y765864D01*
G01X217415Y838066D02*
X322419Y764539D01*
G01X217415Y838066D02*
X322419Y764539D01*
G01X218421Y839072D02*
X322968Y765864D01*
G01X321537Y762398D02*
X215736Y836478D01*
G01X320988Y761073D02*
X214730Y835472D01*
G01X320988Y761073D02*
X214730Y835472D01*
G01X321537Y762398D02*
X215736Y836478D01*
G01X329055Y772292D02*
X745309Y698926D01*
G01X328506Y770967D02*
X745309Y697504D01*
G01X328506Y770967D02*
X745309Y697504D01*
G01X329055Y772292D02*
X745309Y698926D01*
G01X759072Y692808D02*
X324166Y769462D01*
G01X759072Y691386D02*
X323617Y768137D01*
G01X759072Y691386D02*
X323617Y768137D01*
G01X759072Y692808D02*
X324166Y769462D01*
G01X322968Y765864D02*
X831573Y676186D01*
G01X322419Y764539D02*
X831574Y674764D01*
G01X322419Y764539D02*
X831574Y674764D01*
G01X322968Y765864D02*
X831573Y676186D01*
G01X802675Y677557D02*
X321537Y762398D01*
G01X802126Y676232D02*
X320988Y761073D01*
G01X802126Y676232D02*
X320988Y761073D01*
G01X802675Y677557D02*
X321537Y762398D01*
G01X620703Y1082304D02*
X267367Y1144580D01*
G01X620703Y1080882D02*
X266818Y1143255D01*
G01X620703Y1080882D02*
X266818Y1143255D01*
G01X620703Y1082304D02*
X267367Y1144580D01*
G01X662987Y1070922D02*
X266047Y1140911D01*
G01X662987Y1069500D02*
X265498Y1139586D01*
G01X662987Y1069500D02*
X265498Y1139586D01*
G01X662987Y1070922D02*
X266047Y1140911D01*
G01X706277Y1059562D02*
X264878Y1137373D01*
G01X706277Y1058140D02*
X264329Y1136048D01*
G01X706277Y1058140D02*
X264329Y1136048D01*
G01X706277Y1059562D02*
X264878Y1137373D01*
G01X263704Y1133745D02*
X838044Y1032497D01*
G01X263155Y1132420D02*
X838044Y1031075D01*
G01X263155Y1132420D02*
X838044Y1031075D01*
G01X263704Y1133745D02*
X838044Y1032497D01*
G01X352121Y633496D02*
X786795Y329122D01*
G01X351115Y632490D02*
X786246Y327797D01*
G01X351115Y632490D02*
X786246Y327797D01*
G01X352121Y633496D02*
X786795Y329122D01*
G01X813909Y305388D02*
X350037Y630199D01*
G01X813360Y304063D02*
X349031Y629193D01*
G01X813360Y304063D02*
X349031Y629193D01*
G01X813909Y305388D02*
X350037Y630199D01*
G01X840844Y281834D02*
X347098Y627555D01*
G01X840295Y280509D02*
X346092Y626549D01*
G01X840295Y280509D02*
X346092Y626549D01*
G01X840844Y281834D02*
X347098Y627555D01*
G01X814582Y295298D02*
X344972Y624138D01*
G01X813576Y294292D02*
X343966Y623132D01*
G01X813576Y294292D02*
X343966Y623132D01*
G01X814582Y295298D02*
X344972Y624138D01*
G01X867711Y1125858D02*
X620703Y1082304D01*
G01X867834Y1124458D02*
X620703Y1080882D01*
G01X867834Y1124458D02*
X620703Y1080882D01*
G01X867711Y1125858D02*
X620703Y1082304D01*
G01X867377Y1106961D02*
X662987Y1070922D01*
G01X867500Y1105561D02*
X662987Y1069500D01*
G01X867500Y1105561D02*
X662987Y1069500D01*
G01X867377Y1106961D02*
X662987Y1070922D01*
G01X745309Y698926D02*
X866801Y720346D01*
G01X745309Y697504D02*
X866924Y718946D01*
G01X745309Y697504D02*
X866924Y718946D01*
G01X745309Y698926D02*
X866801Y720346D01*
G01X840492Y707166D02*
X759072Y692808D01*
G01X840467Y705739D02*
X759072Y691386D01*
G01X840467Y705739D02*
X759072Y691386D01*
G01X840492Y707166D02*
X759072Y692808D01*
G01X867916Y1088063D02*
X706277Y1059562D01*
G01X868039Y1086663D02*
X706277Y1058140D01*
G01X868039Y1086663D02*
X706277Y1058140D01*
G01X867916Y1088063D02*
X706277Y1059562D01*
G01X748392Y1510331D02*
X867711Y1531370D01*
G01X748633Y1508951D02*
X867834Y1529970D01*
G01X747524Y1510331D02*
G03X748392I434J2462D01*
G01X747279Y1508951D02*
G03X748633I677J3841D01*
G01D02*
X867834Y1529970D01*
G01X748392Y1510331D02*
X867711Y1531370D01*
G01X747279Y1508951D02*
G03X748633I677J3841D01*
G01X747524Y1510331D02*
G03X748392I434J2462D01*
G01X863927Y1936240D02*
X742742Y1851449D01*
G01X864476Y1934914D02*
X743292Y1850124D01*
G01X864476Y1934914D02*
X743292Y1850124D01*
G01X863927Y1936240D02*
X742742Y1851449D01*
G01X859565Y231055D02*
X814582Y295298D01*
G01X858559Y230049D02*
X813576Y294292D01*
G01X858559Y230049D02*
X813576Y294292D01*
G01X859565Y231055D02*
X814582Y295298D01*
G01X786795Y329122D02*
X867834Y314834D01*
G01X786246Y327797D02*
X867711Y313434D01*
G01X786246Y327797D02*
X867711Y313434D01*
G01X786795Y329122D02*
X867834Y314834D01*
G01X867500Y295937D02*
X813909Y305388D01*
G01X867377Y294537D02*
X813360Y304063D01*
G01X867377Y294537D02*
X813360Y304063D01*
G01X867500Y295937D02*
X813909Y305388D01*
G01X831573Y676186D02*
X867670Y682551D01*
G01X831574Y674764D02*
X867793Y681151D01*
G01X831574Y674764D02*
X867793Y681151D01*
G01X831573Y676186D02*
X867670Y682551D01*
G01X867517Y632157D02*
X802675Y677557D01*
G01X867075Y630757D02*
X802126Y676232D01*
G01X867075Y630757D02*
X802126Y676232D01*
G01X867517Y632157D02*
X802675Y677557D01*
G01X838044Y1032497D02*
X867377Y1037669D01*
G01X838044Y1031075D02*
X867500Y1036269D01*
G01X838044Y1031075D02*
X867500Y1036269D01*
G01X838044Y1032497D02*
X867377Y1037669D01*
G01X790919Y1499036D02*
G02X790051I-434J2463D01*
G01X791162Y1497657D02*
G02X789808I-677J3841D01*
G01X867254Y1512473D02*
X790919Y1499036D01*
G01X867377Y1511073D02*
X791162Y1497657D01*
G01D02*
G02X789808I-677J3841D01*
G01X790919Y1499036D02*
G02X790051I-434J2463D01*
G01X867377Y1511073D02*
X791162Y1497657D01*
G01X867254Y1512473D02*
X790919Y1499036D01*
G01X867794Y1493575D02*
X833778Y1487602D01*
G01X867916Y1492175D02*
X833778Y1486180D01*
G01X867916Y1492175D02*
X833778Y1486180D01*
G01X867794Y1493575D02*
X833778Y1487602D01*
G01X802025Y1489027D02*
G03X800466Y1489673I-2237J-3194D01*
G01X801222Y1487880D02*
G03X800222Y1488294I-1434J-2048D01*
G01X867500Y1443181D02*
X802025Y1489027D01*
G01X867058Y1441781D02*
X801222Y1487880D01*
G01D02*
G03X800222Y1488294I-1434J-2048D01*
G01X802025Y1489027D02*
G03X800466Y1489673I-2237J-3194D01*
G01X867058Y1441781D02*
X801222Y1487880D01*
G01X867500Y1443181D02*
X802025Y1489027D01*
G01X768671Y1852133D02*
X861007Y1916774D01*
G01X769220Y1850808D02*
X861556Y1915449D01*
G01X769220Y1850808D02*
X861556Y1915449D01*
G01X768671Y1852133D02*
X861007Y1916774D01*
G01X858879Y1897466D02*
X795112Y1852817D01*
G01X859428Y1896141D02*
X795661Y1851492D01*
G01X859428Y1896141D02*
X795661Y1851492D01*
G01X858879Y1897466D02*
X795112Y1852817D01*
G01X868000Y1848693D02*
X830708Y1855269D01*
G01X867877Y1847293D02*
X830709Y1853847D01*
G01X867877Y1847293D02*
X830709Y1853847D01*
G01X868000Y1848693D02*
X830708Y1855269D01*
G01X865313Y227031D02*
X859565Y231055D01*
G01X864764Y225706D02*
X858559Y230049D01*
G01X867500Y226645D02*
X865313Y227031D01*
G01X867377Y225245D02*
X864764Y225706D01*
G01X871441Y226645D02*
X867500D01*
G01X871441Y225245D02*
X867377D01*
G01X864764Y225706D02*
X858559Y230049D01*
G01X865313Y227031D02*
X859565Y231055D01*
G01X867377Y225245D02*
X864764Y225706D01*
G01X867500Y226645D02*
X865313Y227031D01*
G01X871441Y225245D02*
X867377D01*
G01X871441Y226645D02*
X867500D01*
G01X867834Y314834D02*
X871441D01*
G01X867711Y313434D02*
X871441D01*
G01X867711D02*
X871441D01*
G01X867834Y314834D02*
X871441D01*
G01X871442Y295937D02*
X867500D01*
G01X871440Y294537D02*
X867377D01*
G01X871440D02*
X867377D01*
G01X871442Y295937D02*
X867500D01*
G01X868039Y277039D02*
X840844Y281834D01*
G01X867916Y275639D02*
X840295Y280509D01*
G01X871442Y277039D02*
X868039D01*
G01X871440Y275639D02*
X867916D01*
G01D02*
X840295Y280509D01*
G01X868039Y277039D02*
X840844Y281834D01*
G01X871440Y275639D02*
X867916D01*
G01X871442Y277039D02*
X868039D01*
G01X867379Y701449D02*
X840492Y707166D01*
G01X867231Y700049D02*
X840467Y705739D01*
G01X871442Y701449D02*
X867379D01*
G01X871440Y700049D02*
X867231D01*
G01D02*
X840467Y705739D01*
G01X867379Y701449D02*
X840492Y707166D01*
G01X871440Y700049D02*
X867231D01*
G01X871442Y701449D02*
X867379D01*
G01X867670Y682551D02*
X871442D01*
G01X867793Y681151D02*
X871440D01*
G01X867793D02*
X871440D01*
G01X867670Y682551D02*
X871442D01*
G01X871441Y632157D02*
X867517D01*
G01X871441Y630757D02*
X867075D01*
G01X871441D02*
X867075D01*
G01X871441Y632157D02*
X867517D01*
G01X866801Y720346D02*
X871441D01*
G01X866924Y718946D02*
X871441D01*
G01X866924D02*
X871441D01*
G01X866801Y720346D02*
X871441D01*
G01X867377Y1037669D02*
X871441D01*
G01X867500Y1036269D02*
X871441D01*
G01X867500D02*
X871441D01*
G01X867377Y1037669D02*
X871441D01*
G01Y1125858D02*
X867711D01*
G01X871441Y1124458D02*
X867834D01*
G01X871441D02*
X867834D01*
G01X871441Y1125858D02*
X867711D01*
G01X871442Y1106961D02*
X867377D01*
G01X871440Y1105561D02*
X867500D01*
G01X871440D02*
X867500D01*
G01X871442Y1106961D02*
X867377D01*
G01X871442Y1088063D02*
X867916D01*
G01X871440Y1086663D02*
X868039D01*
G01X871440D02*
X868039D01*
G01X871442Y1088063D02*
X867916D01*
G01X871442Y1493575D02*
X867794D01*
G01X871440Y1492175D02*
X867916D01*
G01X871440D02*
X867916D01*
G01X871442Y1493575D02*
X867794D01*
G01X871441Y1443181D02*
X867500D01*
G01X871441Y1441781D02*
X867058D01*
G01X871441D02*
X867058D01*
G01X871441Y1443181D02*
X867500D01*
G01X867711Y1531370D02*
X871441D01*
G01X867834Y1529970D02*
X871441D01*
G01X867834D02*
X871441D01*
G01X867711Y1531370D02*
X871441D01*
G01X871442Y1512473D02*
X867254D01*
G01X871440Y1511073D02*
X867377D01*
G01X871440D02*
X867377D01*
G01X871442Y1512473D02*
X867254D01*
G01X871441Y1848693D02*
X868000D01*
G01X871441Y1847293D02*
X867877D01*
G01X871441D02*
X867877D01*
G01X871441Y1848693D02*
X868000D01*
G01X867576Y1936882D02*
X863927Y1936240D01*
G01X867699Y1935482D02*
X864476Y1934914D01*
G01X871441Y1936882D02*
X867576D01*
G01X871441Y1935482D02*
X867699D01*
G01D02*
X864476Y1934914D01*
G01X867576Y1936882D02*
X863927Y1936240D01*
G01X871441Y1935482D02*
X867699D01*
G01X871441Y1936882D02*
X867576D01*
G01X867877Y1917985D02*
X871442D01*
G01X868000Y1916585D02*
X871440D01*
G01X861007Y1916774D02*
X867877Y1917985D01*
G01X861556Y1915449D02*
X868000Y1916585D01*
G01D02*
X871440D01*
G01X867877Y1917985D02*
X871442D01*
G01X861556Y1915449D02*
X868000Y1916585D01*
G01X861007Y1916774D02*
X867877Y1917985D01*
G01X868075Y1899087D02*
X858879Y1897466D01*
G01X863812Y1896913D02*
X859428Y1896141D01*
G01X868198Y1897686D02*
X863812Y1896913D01*
G01X871442Y1899087D02*
X868075D01*
G01X871440Y1897687D02*
X868198D01*
G01X863812Y1896913D02*
X859428Y1896141D01*
G01X868075Y1899087D02*
X858879Y1897466D01*
G01X868198Y1897686D02*
X863812Y1896913D01*
G01X868075Y1899087D02*
X858879Y1897466D01*
G01X871440Y1897687D02*
X868198D01*
G01X871442Y1899087D02*
X868075D01*
M02*
